G04 ================== begin FILE IDENTIFICATION RECORD ==================*
G04 Layout Name:  16368-sb.brd*
G04 Film Name:    SE_REF_L4*
G04 File Format:  Gerber RS274X*
G04 File Origin:  Cadence Allegro 16.5-S056*
G04 Origin Date:  Tue Feb 07 09:07:46 2017*
G04 *
G04 Layer:  BOARD GEOMETRY/SE_REF_L4_TBL*
G04 Layer:  BOARD GEOMETRY/SE_REF_L4_L4*
G04 Layer:  BOARD GEOMETRY/PANEL_OUTLINE*
G04 *
G04 Offset:    (0.00 0.00)*
G04 Mirror:    No*
G04 Mode:      Positive*
G04 Rotation:  0*
G04 FullContactRelief:  No*
G04 UndefLineWidth:     6.00*
G04 ================== end FILE IDENTIFICATION RECORD ====================*
%FSLAX35Y35*MOIN*%
%IR0*IPPOS*OFA0.00000B0.00000*MIA0B0*SFA1.00000B1.00000*%
%ADD10C,.02*%
%ADD11C,.005*%
%ADD12C,.006*%
G75*
%LPD*%
G75*
G54D10*
G01X597544Y585326D02*
X1315044D01*
G01X597544Y654626D02*
Y585326D01*
G01Y654626D02*
X1315044D01*
G01X597544Y619976D02*
X1315044D01*
G01X772544Y654626D02*
Y585326D01*
G01X1000044Y654626D02*
Y585326D01*
G01X1105044Y654626D02*
Y585326D01*
G01X1315044Y654626D02*
Y585326D01*
G54D11*
G01X56000Y55500D02*
X53000Y58500D01*
G01D02*
X43500D01*
G01D02*
X34200Y49200D01*
G01D02*
Y47000D01*
G01X111700Y39600D02*
Y40800D01*
G01D02*
X100900Y51600D01*
G01D02*
X90500D01*
G01D02*
X89950Y51050D01*
G01D02*
X67750D01*
G01D02*
X60800Y44100D01*
G01D02*
X53900D01*
G01D02*
X52230Y45770D01*
G01D02*
Y46537D01*
G01D02*
X52218Y46549D01*
G01D02*
Y47067D01*
G01X96000Y55600D02*
X63136D01*
G01D02*
X57336Y49800D01*
G01D02*
X46300D01*
G01D02*
X44607Y48107D01*
G01D02*
Y46831D01*
G01X39300Y35500D02*
X41400Y33400D01*
G01D02*
X57172D01*
G01D02*
X69822Y46050D01*
G01D02*
X88549D01*
G01D02*
X100699Y33900D01*
G01D02*
X119500D01*
G01X36733Y47067D02*
Y48197D01*
G01D02*
X40836Y52300D01*
G01D02*
X56300D01*
G01D02*
X62561Y58561D01*
G01D02*
X121203D01*
G01X45250Y35850D02*
X36733Y44367D01*
G01D02*
Y47067D01*
G01X49730Y46821D02*
Y44734D01*
G01D02*
X52864Y41600D01*
G01D02*
X61836D01*
G01D02*
X68786Y48550D01*
G01D02*
X89585D01*
G01D02*
X99135Y39000D01*
G01D02*
X105000D01*
G01D02*
X107000Y37000D01*
G01D02*
X127500D01*
G01X121203Y58561D02*
X127500Y52264D01*
G54D12*
G01X6250Y-52485D02*
Y-69985D01*
G01X1228Y-52485D02*
X11272D01*
G01X20038Y-69985D02*
Y-52485D01*
G01Y-60943D02*
X21130Y-59485D01*
X22222Y-58610D01*
X23968Y-58319D01*
X25278Y-58610D01*
X26807Y-59777D01*
X27462Y-61527D01*
Y-69985D01*
G01X41250Y-58319D02*
Y-69985D01*
G01Y-53652D02*
X40813Y-53360D01*
Y-52777D01*
X41250Y-52485D01*
X41687Y-52777D01*
Y-53360D01*
X41250Y-53652D01*
G01X55475Y-67944D02*
X56567Y-69110D01*
X58095Y-69985D01*
X59405D01*
X60715Y-69402D01*
X61588Y-68527D01*
X62025Y-67361D01*
X61807Y-65610D01*
X60933Y-64735D01*
X57003Y-62985D01*
X56130Y-60943D01*
X56567Y-59485D01*
X57440Y-58610D01*
X58750Y-58319D01*
X60060Y-58610D01*
X61370Y-59485D01*
G01X90693Y-74360D02*
X92222Y-75527D01*
X93968Y-75818D01*
X95496Y-75527D01*
X96807Y-74069D01*
X97680Y-72027D01*
Y-58319D01*
G01Y-60652D02*
X96807Y-59485D01*
X95496Y-58610D01*
X93968Y-58319D01*
X92222Y-58902D01*
X91130Y-60068D01*
X90256Y-62110D01*
X89820Y-64152D01*
X90038Y-65902D01*
X90912Y-67944D01*
X92222Y-69402D01*
X93968Y-69985D01*
X95278Y-69693D01*
X96807Y-68527D01*
X97680Y-67361D01*
G01X107975Y-62110D02*
X114962D01*
X114307Y-60068D01*
X113215Y-58902D01*
X111687Y-58319D01*
X110158Y-58610D01*
X108848Y-59485D01*
X107975Y-61527D01*
X107538Y-63277D01*
Y-65027D01*
X107975Y-66777D01*
X109067Y-68527D01*
X110377Y-69693D01*
X111905Y-69985D01*
X113433Y-69402D01*
X114962Y-67652D01*
G01X125693Y-69985D02*
Y-58319D01*
G01Y-60652D02*
X126785Y-59485D01*
X127877Y-58610D01*
X129405Y-58319D01*
X130496Y-58610D01*
X131807Y-59485D01*
G01X142320Y-69985D02*
Y-52485D01*
G01Y-61235D02*
X143412Y-59485D01*
X144722Y-58610D01*
X146032Y-58319D01*
X147996Y-58902D01*
X149307Y-60068D01*
X150180Y-62110D01*
Y-64443D01*
X149743Y-66777D01*
X148870Y-68527D01*
X147342Y-69693D01*
X146032Y-69985D01*
X144722Y-69693D01*
X143412Y-68819D01*
X142320Y-67361D01*
G01X160475Y-62110D02*
X167462D01*
X166807Y-60068D01*
X165715Y-58902D01*
X164187Y-58319D01*
X162658Y-58610D01*
X161348Y-59485D01*
X160475Y-61527D01*
X160038Y-63277D01*
Y-65027D01*
X160475Y-66777D01*
X161567Y-68527D01*
X162877Y-69693D01*
X164405Y-69985D01*
X165933Y-69402D01*
X167462Y-67652D01*
G01X178193Y-69985D02*
Y-58319D01*
G01Y-60652D02*
X179285Y-59485D01*
X180377Y-58610D01*
X181905Y-58319D01*
X182996Y-58610D01*
X184307Y-59485D01*
G01X216250Y-58319D02*
Y-69985D01*
G01Y-53652D02*
X215813Y-53360D01*
Y-52777D01*
X216250Y-52485D01*
X216687Y-52777D01*
Y-53360D01*
X216250Y-53652D01*
G01X230475Y-67944D02*
X231567Y-69110D01*
X233095Y-69985D01*
X234405D01*
X235715Y-69402D01*
X236588Y-68527D01*
X237025Y-67361D01*
X236807Y-65610D01*
X235933Y-64735D01*
X232003Y-62985D01*
X231130Y-60943D01*
X231567Y-59485D01*
X232440Y-58610D01*
X233750Y-58319D01*
X235060Y-58610D01*
X236370Y-59485D01*
G01X265256Y-74360D02*
X266785Y-75527D01*
X268095Y-75818D01*
X269842Y-75235D01*
X271152Y-73777D01*
X271807Y-71151D01*
Y-58319D01*
G01Y-53652D02*
X271370Y-53360D01*
Y-52777D01*
X271807Y-52485D01*
X272243Y-52777D01*
Y-53360D01*
X271807Y-53652D01*
G01X282538Y-58319D02*
Y-66485D01*
X283412Y-68527D01*
X284722Y-69693D01*
X286250Y-69985D01*
X287778Y-69693D01*
X289088Y-68527D01*
X289962Y-66485D01*
G01Y-69985D02*
Y-58319D01*
G01X300475Y-67944D02*
X301567Y-69110D01*
X303095Y-69985D01*
X304405D01*
X305715Y-69402D01*
X306588Y-68527D01*
X307025Y-67361D01*
X306807Y-65610D01*
X305933Y-64735D01*
X302003Y-62985D01*
X301130Y-60943D01*
X301567Y-59485D01*
X302440Y-58610D01*
X303750Y-58319D01*
X305060Y-58610D01*
X306370Y-59485D01*
G01X321250Y-52485D02*
Y-69985D01*
G01X318193Y-58319D02*
X324307D01*
G01X354940Y-69985D02*
Y-55110D01*
X355377Y-53652D01*
X356250Y-52777D01*
X357560Y-52485D01*
X358870Y-53068D01*
X359525Y-54527D01*
G01X356905Y-59485D02*
X352538D01*
G01X373750Y-69985D02*
X372440Y-69693D01*
X371130Y-68527D01*
X370256Y-66485D01*
X369820Y-64152D01*
X370256Y-61818D01*
X371130Y-59777D01*
X372440Y-58610D01*
X373750Y-58319D01*
X375060Y-58610D01*
X376370Y-59777D01*
X377243Y-61818D01*
X377462Y-64152D01*
X377243Y-66485D01*
X376370Y-68527D01*
X375060Y-69693D01*
X373750Y-69985D01*
G01X388193D02*
Y-58319D01*
G01Y-60652D02*
X389285Y-59485D01*
X390377Y-58610D01*
X391905Y-58319D01*
X392996Y-58610D01*
X394307Y-59485D01*
G01X421665Y-75235D02*
X422975Y-75818D01*
X424722Y-75235D01*
X425813Y-74069D01*
X426687Y-72610D01*
X427996Y-67944D01*
X430835Y-58319D01*
G01X423848D02*
X427996Y-67944D01*
G01X443750Y-69985D02*
X442440Y-69693D01*
X441130Y-68527D01*
X440256Y-66485D01*
X439820Y-64152D01*
X440256Y-61818D01*
X441130Y-59777D01*
X442440Y-58610D01*
X443750Y-58319D01*
X445060Y-58610D01*
X446370Y-59777D01*
X447243Y-61818D01*
X447462Y-64152D01*
X447243Y-66485D01*
X446370Y-68527D01*
X445060Y-69693D01*
X443750Y-69985D01*
G01X457538Y-58319D02*
Y-66485D01*
X458412Y-68527D01*
X459722Y-69693D01*
X461250Y-69985D01*
X462778Y-69693D01*
X464088Y-68527D01*
X464962Y-66485D01*
G01Y-69985D02*
Y-58319D01*
G01X475693Y-69985D02*
Y-58319D01*
G01Y-60652D02*
X476785Y-59485D01*
X477877Y-58610D01*
X479405Y-58319D01*
X480496Y-58610D01*
X481807Y-59485D01*
G01X510693Y-69985D02*
Y-58319D01*
G01Y-60652D02*
X511785Y-59485D01*
X512877Y-58610D01*
X514405Y-58319D01*
X515496Y-58610D01*
X516807Y-59485D01*
G01X527975Y-62110D02*
X534962D01*
X534307Y-60068D01*
X533215Y-58902D01*
X531687Y-58319D01*
X530158Y-58610D01*
X528848Y-59485D01*
X527975Y-61527D01*
X527538Y-63277D01*
Y-65027D01*
X527975Y-66777D01*
X529067Y-68527D01*
X530377Y-69693D01*
X531905Y-69985D01*
X533433Y-69402D01*
X534962Y-67652D01*
G01X547440Y-69985D02*
Y-55110D01*
X547877Y-53652D01*
X548750Y-52777D01*
X550060Y-52485D01*
X551370Y-53068D01*
X552025Y-54527D01*
G01X549405Y-59485D02*
X545038D01*
G01X562975Y-62110D02*
X569962D01*
X569307Y-60068D01*
X568215Y-58902D01*
X566687Y-58319D01*
X565158Y-58610D01*
X563848Y-59485D01*
X562975Y-61527D01*
X562538Y-63277D01*
Y-65027D01*
X562975Y-66777D01*
X564067Y-68527D01*
X565377Y-69693D01*
X566905Y-69985D01*
X568433Y-69402D01*
X569962Y-67652D01*
G01X580693Y-69985D02*
Y-58319D01*
G01Y-60652D02*
X581785Y-59485D01*
X582877Y-58610D01*
X584405Y-58319D01*
X585496Y-58610D01*
X586807Y-59485D01*
G01X597975Y-62110D02*
X604962D01*
X604307Y-60068D01*
X603215Y-58902D01*
X601687Y-58319D01*
X600158Y-58610D01*
X598848Y-59485D01*
X597975Y-61527D01*
X597538Y-63277D01*
Y-65027D01*
X597975Y-66777D01*
X599067Y-68527D01*
X600377Y-69693D01*
X601905Y-69985D01*
X603433Y-69402D01*
X604962Y-67652D01*
G01X615038Y-69985D02*
Y-58319D01*
G01Y-61235D02*
X615912Y-59777D01*
X617222Y-58610D01*
X618968Y-58319D01*
X620496Y-58610D01*
X621807Y-59777D01*
X622462Y-61818D01*
Y-69985D01*
G01X639743Y-59777D02*
X638215Y-58610D01*
X636905Y-58319D01*
X635158Y-58902D01*
X633848Y-60068D01*
X632975Y-62110D01*
X632756Y-64152D01*
X632975Y-66194D01*
X633848Y-67944D01*
X635158Y-69402D01*
X636905Y-69985D01*
X638433Y-69402D01*
X639743Y-68235D01*
G01X650475Y-62110D02*
X657462D01*
X656807Y-60068D01*
X655715Y-58902D01*
X654187Y-58319D01*
X652658Y-58610D01*
X651348Y-59485D01*
X650475Y-61527D01*
X650038Y-63277D01*
Y-65027D01*
X650475Y-66777D01*
X651567Y-68527D01*
X652877Y-69693D01*
X654405Y-69985D01*
X655933Y-69402D01*
X657462Y-67652D01*
G01X688750Y-52485D02*
Y-69985D01*
G01X685693Y-58319D02*
X691807D01*
G01X706250Y-69985D02*
X704940Y-69693D01*
X703630Y-68527D01*
X702756Y-66485D01*
X702320Y-64152D01*
X702756Y-61818D01*
X703630Y-59777D01*
X704940Y-58610D01*
X706250Y-58319D01*
X707560Y-58610D01*
X708870Y-59777D01*
X709743Y-61818D01*
X709962Y-64152D01*
X709743Y-66485D01*
X708870Y-68527D01*
X707560Y-69693D01*
X706250Y-69985D01*
G01X739940D02*
Y-55110D01*
X740377Y-53652D01*
X741250Y-52777D01*
X742560Y-52485D01*
X743870Y-53068D01*
X744525Y-54527D01*
G01X741905Y-59485D02*
X737538D01*
G01X758750Y-58319D02*
Y-69985D01*
G01Y-53652D02*
X758313Y-53360D01*
Y-52777D01*
X758750Y-52485D01*
X759187Y-52777D01*
Y-53360D01*
X758750Y-53652D01*
G01X772538Y-69985D02*
Y-58319D01*
G01Y-61235D02*
X773412Y-59777D01*
X774722Y-58610D01*
X776468Y-58319D01*
X777996Y-58610D01*
X779307Y-59777D01*
X779962Y-61818D01*
Y-69985D01*
G01X797680Y-52485D02*
Y-69985D01*
G01Y-67361D02*
X796807Y-68819D01*
X795496Y-69693D01*
X793968Y-69985D01*
X792222Y-69402D01*
X790912Y-67944D01*
X790038Y-66194D01*
X789820Y-64152D01*
X790038Y-62110D01*
X790912Y-60360D01*
X792222Y-58902D01*
X793968Y-58319D01*
X795496Y-58610D01*
X796588Y-59194D01*
X797680Y-60360D01*
G01X828750Y-52485D02*
Y-69985D01*
G01X825693Y-58319D02*
X831807D01*
G01X842538Y-69985D02*
Y-52485D01*
G01Y-60943D02*
X843630Y-59485D01*
X844722Y-58610D01*
X846468Y-58319D01*
X847778Y-58610D01*
X849307Y-59777D01*
X849962Y-61527D01*
Y-69985D01*
G01X860475Y-62110D02*
X867462D01*
X866807Y-60068D01*
X865715Y-58902D01*
X864187Y-58319D01*
X862658Y-58610D01*
X861348Y-59485D01*
X860475Y-61527D01*
X860038Y-63277D01*
Y-65027D01*
X860475Y-66777D01*
X861567Y-68527D01*
X862877Y-69693D01*
X864405Y-69985D01*
X865933Y-69402D01*
X867462Y-67652D01*
G01X894165D02*
X895912Y-69110D01*
X897877Y-69985D01*
X899623D01*
X901370Y-69110D01*
X902680Y-67652D01*
X903335Y-65610D01*
X902898Y-63569D01*
X901807Y-61818D01*
X899842Y-60652D01*
X897222Y-60068D01*
X895693Y-58902D01*
X895038Y-56860D01*
X895475Y-54818D01*
X896567Y-53360D01*
X898095Y-52485D01*
X899623D01*
X901152Y-53068D01*
X902462Y-54527D01*
G01X920617Y-69985D02*
X911883D01*
Y-52485D01*
X920617D01*
G01X917123Y-60943D02*
X911883D01*
G01X951250Y-58319D02*
Y-69985D01*
G01Y-53652D02*
X950813Y-53360D01*
Y-52777D01*
X951250Y-52485D01*
X951687Y-52777D01*
Y-53360D01*
X951250Y-53652D01*
G01X962200Y-69985D02*
Y-58319D01*
G01Y-61527D02*
X962855Y-60068D01*
X963947Y-58902D01*
X965475Y-58319D01*
X967003Y-58902D01*
X968095Y-60068D01*
X968750Y-61527D01*
Y-69985D01*
G01Y-61527D02*
X969405Y-60068D01*
X970496Y-58902D01*
X972025Y-58319D01*
X973553Y-58902D01*
X974645Y-60068D01*
X975300Y-61818D01*
Y-69985D01*
G01X982320Y-75818D02*
Y-58319D01*
G01Y-60943D02*
X983412Y-59485D01*
X984503Y-58610D01*
X986250Y-58319D01*
X987778Y-58610D01*
X989307Y-60068D01*
X989962Y-62110D01*
X990180Y-64152D01*
X989962Y-66194D01*
X989307Y-68235D01*
X987996Y-69402D01*
X986250Y-69985D01*
X984722Y-69693D01*
X983193Y-68819D01*
X982320Y-67652D01*
G01X1000475Y-62110D02*
X1007462D01*
X1006807Y-60068D01*
X1005715Y-58902D01*
X1004187Y-58319D01*
X1002658Y-58610D01*
X1001348Y-59485D01*
X1000475Y-61527D01*
X1000038Y-63277D01*
Y-65027D01*
X1000475Y-66777D01*
X1001567Y-68527D01*
X1002877Y-69693D01*
X1004405Y-69985D01*
X1005933Y-69402D01*
X1007462Y-67652D01*
G01X1025180Y-52485D02*
Y-69985D01*
G01Y-67361D02*
X1024307Y-68819D01*
X1022996Y-69693D01*
X1021468Y-69985D01*
X1019722Y-69402D01*
X1018412Y-67944D01*
X1017538Y-66194D01*
X1017320Y-64152D01*
X1017538Y-62110D01*
X1018412Y-60360D01*
X1019722Y-58902D01*
X1021468Y-58319D01*
X1022996Y-58610D01*
X1024088Y-59194D01*
X1025180Y-60360D01*
G01X1042680Y-69985D02*
Y-58319D01*
G01Y-60360D02*
X1041807Y-59194D01*
X1040496Y-58610D01*
X1038968Y-58319D01*
X1037440Y-58902D01*
X1036130Y-60068D01*
X1035256Y-61818D01*
X1034820Y-64152D01*
X1035256Y-66485D01*
X1036130Y-68235D01*
X1037440Y-69402D01*
X1038968Y-69985D01*
X1040496Y-69693D01*
X1041807Y-68819D01*
X1042680Y-67652D01*
G01X1052538Y-69985D02*
Y-58319D01*
G01Y-61235D02*
X1053412Y-59777D01*
X1054722Y-58610D01*
X1056468Y-58319D01*
X1057996Y-58610D01*
X1059307Y-59777D01*
X1059962Y-61818D01*
Y-69985D01*
G01X1077243Y-59777D02*
X1075715Y-58610D01*
X1074405Y-58319D01*
X1072658Y-58902D01*
X1071348Y-60068D01*
X1070475Y-62110D01*
X1070256Y-64152D01*
X1070475Y-66194D01*
X1071348Y-67944D01*
X1072658Y-69402D01*
X1074405Y-69985D01*
X1075933Y-69402D01*
X1077243Y-68235D01*
G01X1087975Y-62110D02*
X1094962D01*
X1094307Y-60068D01*
X1093215Y-58902D01*
X1091687Y-58319D01*
X1090158Y-58610D01*
X1088848Y-59485D01*
X1087975Y-61527D01*
X1087538Y-63277D01*
Y-65027D01*
X1087975Y-66777D01*
X1089067Y-68527D01*
X1090377Y-69693D01*
X1091905Y-69985D01*
X1093433Y-69402D01*
X1094962Y-67652D01*
G01X1126250Y-52485D02*
Y-69985D01*
G01X1123193Y-58319D02*
X1129307D01*
G01X1140693Y-69985D02*
Y-58319D01*
G01Y-60652D02*
X1141785Y-59485D01*
X1142877Y-58610D01*
X1144405Y-58319D01*
X1145496Y-58610D01*
X1146807Y-59485D01*
G01X1165180Y-69985D02*
Y-58319D01*
G01Y-60360D02*
X1164307Y-59194D01*
X1162996Y-58610D01*
X1161468Y-58319D01*
X1159940Y-58902D01*
X1158630Y-60068D01*
X1157756Y-61818D01*
X1157320Y-64152D01*
X1157756Y-66485D01*
X1158630Y-68235D01*
X1159940Y-69402D01*
X1161468Y-69985D01*
X1162996Y-69693D01*
X1164307Y-68819D01*
X1165180Y-67652D01*
G01X1182243Y-59777D02*
X1180715Y-58610D01*
X1179405Y-58319D01*
X1177658Y-58902D01*
X1176348Y-60068D01*
X1175475Y-62110D01*
X1175256Y-64152D01*
X1175475Y-66194D01*
X1176348Y-67944D01*
X1177658Y-69402D01*
X1179405Y-69985D01*
X1180933Y-69402D01*
X1182243Y-68235D01*
G01X1192975Y-62110D02*
X1199962D01*
X1199307Y-60068D01*
X1198215Y-58902D01*
X1196687Y-58319D01*
X1195158Y-58610D01*
X1193848Y-59485D01*
X1192975Y-61527D01*
X1192538Y-63277D01*
Y-65027D01*
X1192975Y-66777D01*
X1194067Y-68527D01*
X1195377Y-69693D01*
X1196905Y-69985D01*
X1198433Y-69402D01*
X1199962Y-67652D01*
G01X1210475Y-67944D02*
X1211567Y-69110D01*
X1213095Y-69985D01*
X1214405D01*
X1215715Y-69402D01*
X1216588Y-68527D01*
X1217025Y-67361D01*
X1216807Y-65610D01*
X1215933Y-64735D01*
X1212003Y-62985D01*
X1211130Y-60943D01*
X1211567Y-59485D01*
X1212440Y-58610D01*
X1213750Y-58319D01*
X1215060Y-58610D01*
X1216370Y-59485D01*
G01X1248750Y-58319D02*
Y-69985D01*
G01Y-53652D02*
X1248313Y-53360D01*
Y-52777D01*
X1248750Y-52485D01*
X1249187Y-52777D01*
Y-53360D01*
X1248750Y-53652D01*
G01X1262538Y-69985D02*
Y-58319D01*
G01Y-61235D02*
X1263412Y-59777D01*
X1264722Y-58610D01*
X1266468Y-58319D01*
X1267996Y-58610D01*
X1269307Y-59777D01*
X1269962Y-61818D01*
Y-69985D01*
G01X1301250D02*
Y-52485D01*
G01X1322680Y-69985D02*
Y-58319D01*
G01Y-60360D02*
X1321807Y-59194D01*
X1320496Y-58610D01*
X1318968Y-58319D01*
X1317440Y-58902D01*
X1316130Y-60068D01*
X1315256Y-61818D01*
X1314820Y-64152D01*
X1315256Y-66485D01*
X1316130Y-68235D01*
X1317440Y-69402D01*
X1318968Y-69985D01*
X1320496Y-69693D01*
X1321807Y-68819D01*
X1322680Y-67652D01*
G01X1331665Y-75235D02*
X1332975Y-75818D01*
X1334722Y-75235D01*
X1335813Y-74069D01*
X1336687Y-72610D01*
X1337996Y-67944D01*
X1340835Y-58319D01*
G01X1333848D02*
X1337996Y-67944D01*
G01X1350475Y-62110D02*
X1357462D01*
X1356807Y-60068D01*
X1355715Y-58902D01*
X1354187Y-58319D01*
X1352658Y-58610D01*
X1351348Y-59485D01*
X1350475Y-61527D01*
X1350038Y-63277D01*
Y-65027D01*
X1350475Y-66777D01*
X1351567Y-68527D01*
X1352877Y-69693D01*
X1354405Y-69985D01*
X1355933Y-69402D01*
X1357462Y-67652D01*
G01X1368193Y-69985D02*
Y-58319D01*
G01Y-60652D02*
X1369285Y-59485D01*
X1370377Y-58610D01*
X1371905Y-58319D01*
X1372996Y-58610D01*
X1374307Y-59485D01*
G01X1401883Y-52485D02*
Y-69985D01*
X1410617D01*
G01X1426370D02*
Y-52485D01*
X1418291Y-65027D01*
X1429209D01*
G01X1441250Y-70568D02*
X1440813Y-70277D01*
Y-69693D01*
X1441250Y-69402D01*
X1441687Y-69693D01*
Y-70277D01*
X1441250Y-70568D01*
G01X599509Y666709D02*
X601256Y665251D01*
X603221Y664376D01*
X604967D01*
X606714Y665251D01*
X608024Y666709D01*
X608679Y668751D01*
X608242Y670792D01*
X607151Y672543D01*
X605186Y673709D01*
X602566Y674293D01*
X601037Y675459D01*
X600382Y677501D01*
X600819Y679543D01*
X601911Y681001D01*
X603439Y681876D01*
X604967D01*
X606496Y681293D01*
X607806Y679834D01*
G01X625961Y664376D02*
X617227D01*
Y681876D01*
X625961D01*
G01X622467Y673418D02*
X617227D01*
G01X653974Y681876D02*
X659214D01*
G01X656594D02*
Y664376D01*
G01X653974D02*
X659214D01*
G01X668417D02*
Y681876D01*
X674094Y667293D01*
X679771Y681876D01*
Y664376D01*
G01X687227D02*
Y681876D01*
X692467D01*
X694214Y681001D01*
X695524Y678959D01*
X695961Y676626D01*
X695524Y674293D01*
X694432Y672543D01*
X692467Y671667D01*
X687227D01*
G01X713461Y664376D02*
X704727D01*
Y681876D01*
X713461D01*
G01X709967Y673418D02*
X704727D01*
G01X721791Y664376D02*
Y681876D01*
X726157D01*
X727904Y681001D01*
X729214Y679834D01*
X730306Y678085D01*
X731179Y676042D01*
X731397Y673126D01*
X731179Y670209D01*
X730306Y668167D01*
X729214Y666417D01*
X727904Y665251D01*
X726157Y664376D01*
X721791D01*
G01X738635D02*
X744094Y681876D01*
X749553Y664376D01*
G01X747587Y670501D02*
X740600D01*
G01X756572Y664376D02*
Y681876D01*
X766616Y664376D01*
Y681876D01*
G01X783897Y680417D02*
X782587Y681293D01*
X781059Y681876D01*
X779312D01*
X777347Y681001D01*
X775819Y679543D01*
X774727Y677792D01*
X773854Y674876D01*
X773635Y672251D01*
X774072Y669626D01*
X774727Y667876D01*
X776037Y666126D01*
X777566Y664959D01*
X779094Y664376D01*
X780622D01*
X782151Y664959D01*
X783461Y665834D01*
X784553Y667000D01*
G01X800961Y664376D02*
X792227D01*
Y681876D01*
X800961D01*
G01X797467Y673418D02*
X792227D01*
G01X831594Y681876D02*
Y664376D01*
G01X826572Y681876D02*
X836616D01*
G01X843635Y664376D02*
X849094Y681876D01*
X854553Y664376D01*
G01X852587Y670501D02*
X845600D01*
G01X868340Y673709D02*
X869214Y674584D01*
X869869Y676042D01*
X870306Y678085D01*
X869869Y679834D01*
X868996Y681001D01*
X867467Y681876D01*
X861572D01*
Y664376D01*
X868777D01*
X870306Y665542D01*
X871179Y667293D01*
X871616Y669334D01*
X871179Y671376D01*
X869869Y673126D01*
X868340Y673709D01*
X861572D01*
G01X879727Y681876D02*
Y664376D01*
X888461D01*
G01X905961D02*
X897227D01*
Y681876D01*
X905961D01*
G01X902467Y673418D02*
X897227D01*
G01X919094Y663793D02*
X918657Y664084D01*
Y664668D01*
X919094Y664959D01*
X919531Y664668D01*
Y664084D01*
X919094Y663793D01*
G01Y671667D02*
X918657Y671959D01*
Y672543D01*
X919094Y672834D01*
X919531Y672543D01*
Y671959D01*
X919094Y671667D01*
G01X949727Y681876D02*
Y664376D01*
X958461D01*
G01X974214D02*
Y681876D01*
X966135Y669334D01*
X977053D01*
G01X653991Y597700D02*
X655300Y596242D01*
X656829Y595368D01*
X658794Y595076D01*
X660759Y595659D01*
X662287Y596826D01*
X663379Y598867D01*
X663597Y601201D01*
X663161Y603534D01*
X662069Y604993D01*
X660540Y606159D01*
X659012Y606451D01*
X657484Y606159D01*
X655519Y604993D01*
X656174Y612576D01*
X662069D01*
G01X676294D02*
X674547Y611993D01*
X673237Y610534D01*
X672364Y608785D01*
X671709Y606451D01*
X671491Y603826D01*
X671709Y601201D01*
X672364Y598867D01*
X673237Y597117D01*
X674547Y595659D01*
X676294Y595076D01*
X678040Y595659D01*
X679351Y597117D01*
X680224Y598867D01*
X680879Y601201D01*
X681097Y603826D01*
X680879Y606451D01*
X680224Y608785D01*
X679351Y610534D01*
X678040Y611993D01*
X676294Y612576D01*
G01X693794Y594493D02*
X693357Y594784D01*
Y595368D01*
X693794Y595659D01*
X694231Y595368D01*
Y594784D01*
X693794Y594493D01*
G01X711294Y612576D02*
X709547Y611993D01*
X708237Y610534D01*
X707364Y608785D01*
X706709Y606451D01*
X706491Y603826D01*
X706709Y601201D01*
X707364Y598867D01*
X708237Y597117D01*
X709547Y595659D01*
X711294Y595076D01*
X713040Y595659D01*
X714351Y597117D01*
X715224Y598867D01*
X715879Y601201D01*
X716097Y603826D01*
X715879Y606451D01*
X715224Y608785D01*
X714351Y610534D01*
X713040Y611993D01*
X711294Y612576D01*
G01X621174Y647226D02*
X626414D01*
G01X623794D02*
Y629726D01*
G01X621174D02*
X626414D01*
G01X635617D02*
Y647226D01*
X641294Y632643D01*
X646971Y647226D01*
Y629726D01*
G01X654427D02*
Y647226D01*
X659667D01*
X661414Y646351D01*
X662724Y644309D01*
X663161Y641976D01*
X662724Y639643D01*
X661632Y637893D01*
X659667Y637017D01*
X654427D01*
G01X675202Y623893D02*
X673019Y626809D01*
X671927Y629726D01*
Y641392D01*
X673019Y644309D01*
X675202Y647226D01*
G01X693794Y629726D02*
X692047Y630018D01*
X690519Y631184D01*
X689209Y632934D01*
X688335Y634976D01*
X687899Y637309D01*
Y639643D01*
X688335Y641976D01*
X689209Y644018D01*
X690519Y645767D01*
X692047Y646934D01*
X693794Y647226D01*
X695540Y646934D01*
X697069Y645767D01*
X698379Y644018D01*
X699253Y641976D01*
X699689Y639643D01*
Y637309D01*
X699253Y634976D01*
X698379Y632934D01*
X697069Y631184D01*
X695540Y630018D01*
X693794Y629726D01*
G01X707582D02*
Y647226D01*
G01Y638768D02*
X708674Y640226D01*
X709766Y641101D01*
X711512Y641392D01*
X712822Y641101D01*
X714351Y639934D01*
X715006Y638184D01*
Y629726D01*
G01X722244D02*
Y641392D01*
G01Y638184D02*
X722899Y639643D01*
X723991Y640809D01*
X725519Y641392D01*
X727047Y640809D01*
X728139Y639643D01*
X728794Y638184D01*
Y629726D01*
G01Y638184D02*
X729449Y639643D01*
X730540Y640809D01*
X732069Y641392D01*
X733597Y640809D01*
X734689Y639643D01*
X735344Y637893D01*
Y629726D01*
G01X747386Y623893D02*
X749569Y626809D01*
X750661Y629726D01*
Y641392D01*
X749569Y644309D01*
X747386Y647226D01*
G01X792244D02*
X795300Y629726D01*
X798794Y647226D01*
X802287Y629726D01*
X805344Y647226D01*
G01X813674D02*
X818914D01*
G01X816294D02*
Y629726D01*
G01X813674D02*
X818914D01*
G01X828991D02*
Y647226D01*
X833357D01*
X835104Y646351D01*
X836414Y645184D01*
X837506Y643435D01*
X838379Y641392D01*
X838597Y638476D01*
X838379Y635559D01*
X837506Y633517D01*
X836414Y631767D01*
X835104Y630601D01*
X833357Y629726D01*
X828991D01*
G01X851294Y647226D02*
Y629726D01*
G01X846272Y647226D02*
X856316D01*
G01X864209Y629726D02*
Y647226D01*
G01X873379D02*
Y629726D01*
G01Y638476D02*
X864209D01*
G01X885202Y623893D02*
X883019Y626809D01*
X881927Y629726D01*
Y641392D01*
X883019Y644309D01*
X885202Y647226D01*
G01X897244Y629726D02*
Y641392D01*
G01Y638184D02*
X897899Y639643D01*
X898991Y640809D01*
X900519Y641392D01*
X902047Y640809D01*
X903139Y639643D01*
X903794Y638184D01*
Y629726D01*
G01Y638184D02*
X904449Y639643D01*
X905540Y640809D01*
X907069Y641392D01*
X908597Y640809D01*
X909689Y639643D01*
X910344Y637893D01*
Y629726D01*
G01X921294Y641392D02*
Y629726D01*
G01Y646059D02*
X920857Y646351D01*
Y646934D01*
X921294Y647226D01*
X921731Y646934D01*
Y646351D01*
X921294Y646059D01*
G01X938794Y629726D02*
Y647226D01*
G01X953019Y631767D02*
X954111Y630601D01*
X955639Y629726D01*
X956949D01*
X958259Y630309D01*
X959132Y631184D01*
X959569Y632350D01*
X959351Y634101D01*
X958477Y634976D01*
X954547Y636726D01*
X953674Y638768D01*
X954111Y640226D01*
X954984Y641101D01*
X956294Y641392D01*
X957604Y641101D01*
X958914Y640226D01*
G01X974886Y623893D02*
X977069Y626809D01*
X978161Y629726D01*
Y641392D01*
X977069Y644309D01*
X974886Y647226D01*
G01X863991Y597700D02*
X865300Y596242D01*
X866829Y595368D01*
X868794Y595076D01*
X870759Y595659D01*
X872287Y596826D01*
X873379Y598867D01*
X873597Y601201D01*
X873161Y603534D01*
X872069Y604993D01*
X870540Y606159D01*
X869012Y606451D01*
X867484Y606159D01*
X865519Y604993D01*
X866174Y612576D01*
X872069D01*
G01X886294Y594493D02*
X885857Y594784D01*
Y595368D01*
X886294Y595659D01*
X886731Y595368D01*
Y594784D01*
X886294Y594493D01*
G01X903794Y612576D02*
X902047Y611993D01*
X900737Y610534D01*
X899864Y608785D01*
X899209Y606451D01*
X898991Y603826D01*
X899209Y601201D01*
X899864Y598867D01*
X900737Y597117D01*
X902047Y595659D01*
X903794Y595076D01*
X905540Y595659D01*
X906851Y597117D01*
X907724Y598867D01*
X908379Y601201D01*
X908597Y603826D01*
X908379Y606451D01*
X907724Y608785D01*
X906851Y610534D01*
X905540Y611993D01*
X903794Y612576D01*
G01X1026294Y647226D02*
Y629726D01*
G01X1021272Y647226D02*
X1031316D01*
G01X1043794Y629726D02*
Y637601D01*
X1039427Y647226D01*
G01X1048161D02*
X1043794Y637601D01*
G01X1056927Y629726D02*
Y647226D01*
X1062167D01*
X1063914Y646351D01*
X1065224Y644309D01*
X1065661Y641976D01*
X1065224Y639643D01*
X1064132Y637893D01*
X1062167Y637017D01*
X1056927D01*
G01X1083161Y629726D02*
X1074427D01*
Y647226D01*
X1083161D01*
G01X1079667Y638768D02*
X1074427D01*
G01X1039209Y597409D02*
X1040956Y595951D01*
X1042921Y595076D01*
X1044667D01*
X1046414Y595951D01*
X1047724Y597409D01*
X1048379Y599451D01*
X1047942Y601492D01*
X1046851Y603243D01*
X1044886Y604409D01*
X1042266Y604993D01*
X1040737Y606159D01*
X1040082Y608201D01*
X1040519Y610243D01*
X1041611Y611701D01*
X1043139Y612576D01*
X1044667D01*
X1046196Y611993D01*
X1047506Y610534D01*
G01X1065661Y595076D02*
X1056927D01*
Y612576D01*
X1065661D01*
G01X1062167Y604118D02*
X1056927D01*
G01X1170677Y612576D02*
Y595076D01*
X1179411D01*
G01X1188396Y609659D02*
X1189706Y611409D01*
X1191234Y612284D01*
X1192981Y612576D01*
X1195164Y611993D01*
X1196692Y610534D01*
X1197129Y608785D01*
X1196911Y607034D01*
X1196037Y605576D01*
X1191671Y602659D01*
X1189706Y600618D01*
X1188396Y597700D01*
X1187959Y595076D01*
X1197129D01*
G01X1206114Y594493D02*
X1213974Y612576D01*
G01X1223177D02*
Y595076D01*
X1231911D01*
G01X1240241Y597700D02*
X1241550Y596242D01*
X1243079Y595368D01*
X1245044Y595076D01*
X1247009Y595659D01*
X1248537Y596826D01*
X1249629Y598867D01*
X1249847Y601201D01*
X1249411Y603534D01*
X1248319Y604993D01*
X1246790Y606159D01*
X1245262Y606451D01*
X1243734Y606159D01*
X1241769Y604993D01*
X1242424Y612576D01*
X1248319D01*
G01X1126927Y629726D02*
Y647226D01*
X1132386D01*
X1134132Y646351D01*
X1135224Y645184D01*
X1135661Y642851D01*
X1135224Y640517D01*
X1133914Y639059D01*
X1132386Y638184D01*
X1126927D01*
G01X1132386D02*
X1135661Y629726D01*
G01X1145519Y637601D02*
X1152506D01*
X1151851Y639643D01*
X1150759Y640809D01*
X1149231Y641392D01*
X1147702Y641101D01*
X1146392Y640226D01*
X1145519Y638184D01*
X1145082Y636434D01*
Y634684D01*
X1145519Y632934D01*
X1146611Y631184D01*
X1147921Y630018D01*
X1149449Y629726D01*
X1150977Y630309D01*
X1152506Y632059D01*
G01X1164984Y629726D02*
Y644601D01*
X1165421Y646059D01*
X1166294Y646934D01*
X1167604Y647226D01*
X1168914Y646643D01*
X1169569Y645184D01*
G01X1166949Y640226D02*
X1162582D01*
G01X1183794Y629143D02*
X1183357Y629434D01*
Y630018D01*
X1183794Y630309D01*
X1184231Y630018D01*
Y629434D01*
X1183794Y629143D01*
G01X1214427Y629726D02*
Y647226D01*
X1219667D01*
X1221414Y646351D01*
X1222724Y644309D01*
X1223161Y641976D01*
X1222724Y639643D01*
X1221632Y637893D01*
X1219667Y637017D01*
X1214427D01*
G01X1236294Y629726D02*
Y647226D01*
G01X1257724Y629726D02*
Y641392D01*
G01Y639351D02*
X1256851Y640517D01*
X1255540Y641101D01*
X1254012Y641392D01*
X1252484Y640809D01*
X1251174Y639643D01*
X1250300Y637893D01*
X1249864Y635559D01*
X1250300Y633226D01*
X1251174Y631476D01*
X1252484Y630309D01*
X1254012Y629726D01*
X1255540Y630018D01*
X1256851Y630892D01*
X1257724Y632059D01*
G01X1267582Y629726D02*
Y641392D01*
G01Y638476D02*
X1268456Y639934D01*
X1269766Y641101D01*
X1271512Y641392D01*
X1273040Y641101D01*
X1274351Y639934D01*
X1275006Y637893D01*
Y629726D01*
G01X1285519Y637601D02*
X1292506D01*
X1291851Y639643D01*
X1290759Y640809D01*
X1289231Y641392D01*
X1287702Y641101D01*
X1286392Y640226D01*
X1285519Y638184D01*
X1285082Y636434D01*
Y634684D01*
X1285519Y632934D01*
X1286611Y631184D01*
X1287921Y630018D01*
X1289449Y629726D01*
X1290977Y630309D01*
X1292506Y632059D01*
G01X1406594Y606742D02*
Y595076D01*
G01Y611409D02*
X1406157Y611701D01*
Y612284D01*
X1406594Y612576D01*
X1407031Y612284D01*
Y611701D01*
X1406594Y611409D01*
G01X1420819Y597117D02*
X1421911Y595951D01*
X1423439Y595076D01*
X1424749D01*
X1426059Y595659D01*
X1426932Y596534D01*
X1427369Y597700D01*
X1427151Y599451D01*
X1426277Y600326D01*
X1422347Y602076D01*
X1421474Y604118D01*
X1421911Y605576D01*
X1422784Y606451D01*
X1424094Y606742D01*
X1425404Y606451D01*
X1426714Y605576D01*
G01X1454072Y595076D02*
Y612576D01*
X1464116Y595076D01*
Y612576D01*
G01X1476594Y595076D02*
X1474847Y595368D01*
X1473319Y596534D01*
X1472009Y598284D01*
X1471135Y600326D01*
X1470699Y602659D01*
Y604993D01*
X1471135Y607326D01*
X1472009Y609368D01*
X1473319Y611117D01*
X1474847Y612284D01*
X1476594Y612576D01*
X1478340Y612284D01*
X1479869Y611117D01*
X1481179Y609368D01*
X1482053Y607326D01*
X1482489Y604993D01*
Y602659D01*
X1482053Y600326D01*
X1481179Y598284D01*
X1479869Y596534D01*
X1478340Y595368D01*
X1476594Y595076D01*
G01X1494094Y612576D02*
Y595076D01*
G01X1489072Y612576D02*
X1499116D01*
G01X1525382Y606742D02*
Y598576D01*
X1526256Y596534D01*
X1527566Y595368D01*
X1529094Y595076D01*
X1530622Y595368D01*
X1531932Y596534D01*
X1532806Y598576D01*
G01Y595076D02*
Y606742D01*
G01X1543319Y597117D02*
X1544411Y595951D01*
X1545939Y595076D01*
X1547249D01*
X1548559Y595659D01*
X1549432Y596534D01*
X1549869Y597700D01*
X1549651Y599451D01*
X1548777Y600326D01*
X1544847Y602076D01*
X1543974Y604118D01*
X1544411Y605576D01*
X1545284Y606451D01*
X1546594Y606742D01*
X1547904Y606451D01*
X1549214Y605576D01*
G01X1560819Y602951D02*
X1567806D01*
X1567151Y604993D01*
X1566059Y606159D01*
X1564531Y606742D01*
X1563002Y606451D01*
X1561692Y605576D01*
X1560819Y603534D01*
X1560382Y601784D01*
Y600034D01*
X1560819Y598284D01*
X1561911Y596534D01*
X1563221Y595368D01*
X1564749Y595076D01*
X1566277Y595659D01*
X1567806Y597409D01*
G01X1585524Y612576D02*
Y595076D01*
G01Y597700D02*
X1584651Y596242D01*
X1583340Y595368D01*
X1581812Y595076D01*
X1580066Y595659D01*
X1578756Y597117D01*
X1577882Y598867D01*
X1577664Y600909D01*
X1577882Y602951D01*
X1578756Y604701D01*
X1580066Y606159D01*
X1581812Y606742D01*
X1583340Y606451D01*
X1584432Y605867D01*
X1585524Y604701D01*
G01X1616594Y606742D02*
Y595076D01*
G01Y611409D02*
X1616157Y611701D01*
Y612284D01*
X1616594Y612576D01*
X1617031Y612284D01*
Y611701D01*
X1616594Y611409D01*
G01X1630382Y595076D02*
Y606742D01*
G01Y603826D02*
X1631256Y605284D01*
X1632566Y606451D01*
X1634312Y606742D01*
X1635840Y606451D01*
X1637151Y605284D01*
X1637806Y603243D01*
Y595076D01*
G01X1669094Y612576D02*
Y595076D01*
G01X1666037Y606742D02*
X1672151D01*
G01X1682882Y595076D02*
Y612576D01*
G01Y604118D02*
X1683974Y605576D01*
X1685066Y606451D01*
X1686812Y606742D01*
X1688122Y606451D01*
X1689651Y605284D01*
X1690306Y603534D01*
Y595076D01*
G01X1704094Y606742D02*
Y595076D01*
G01Y611409D02*
X1703657Y611701D01*
Y612284D01*
X1704094Y612576D01*
X1704531Y612284D01*
Y611701D01*
X1704094Y611409D01*
G01X1718319Y597117D02*
X1719411Y595951D01*
X1720939Y595076D01*
X1722249D01*
X1723559Y595659D01*
X1724432Y596534D01*
X1724869Y597700D01*
X1724651Y599451D01*
X1723777Y600326D01*
X1719847Y602076D01*
X1718974Y604118D01*
X1719411Y605576D01*
X1720284Y606451D01*
X1721594Y606742D01*
X1722904Y606451D01*
X1724214Y605576D01*
G01X1756594Y595076D02*
Y612576D01*
G01X1778024Y595076D02*
Y606742D01*
G01Y604701D02*
X1777151Y605867D01*
X1775840Y606451D01*
X1774312Y606742D01*
X1772784Y606159D01*
X1771474Y604993D01*
X1770600Y603243D01*
X1770164Y600909D01*
X1770600Y598576D01*
X1771474Y596826D01*
X1772784Y595659D01*
X1774312Y595076D01*
X1775840Y595368D01*
X1777151Y596242D01*
X1778024Y597409D01*
G01X1787009Y589826D02*
X1788319Y589243D01*
X1790066Y589826D01*
X1791157Y590992D01*
X1792031Y592451D01*
X1793340Y597117D01*
X1796179Y606742D01*
G01X1789192D02*
X1793340Y597117D01*
G01X1805819Y602951D02*
X1812806D01*
X1812151Y604993D01*
X1811059Y606159D01*
X1809531Y606742D01*
X1808002Y606451D01*
X1806692Y605576D01*
X1805819Y603534D01*
X1805382Y601784D01*
Y600034D01*
X1805819Y598284D01*
X1806911Y596534D01*
X1808221Y595368D01*
X1809749Y595076D01*
X1811277Y595659D01*
X1812806Y597409D01*
G01X1823537Y595076D02*
Y606742D01*
G01Y604409D02*
X1824629Y605576D01*
X1825721Y606451D01*
X1827249Y606742D01*
X1828340Y606451D01*
X1829651Y605576D01*
G01X1406594Y572092D02*
Y560426D01*
G01Y576759D02*
X1406157Y577051D01*
Y577634D01*
X1406594Y577926D01*
X1407031Y577634D01*
Y577051D01*
X1406594Y576759D01*
G01X1420382Y560426D02*
Y572092D01*
G01Y569176D02*
X1421256Y570634D01*
X1422566Y571801D01*
X1424312Y572092D01*
X1425840Y571801D01*
X1427151Y570634D01*
X1427806Y568593D01*
Y560426D01*
G01X1438319Y562467D02*
X1439411Y561301D01*
X1440939Y560426D01*
X1442249D01*
X1443559Y561009D01*
X1444432Y561884D01*
X1444869Y563050D01*
X1444651Y564801D01*
X1443777Y565676D01*
X1439847Y567426D01*
X1438974Y569468D01*
X1439411Y570926D01*
X1440284Y571801D01*
X1441594Y572092D01*
X1442904Y571801D01*
X1444214Y570926D01*
G01X1459094Y572092D02*
Y560426D01*
G01Y576759D02*
X1458657Y577051D01*
Y577634D01*
X1459094Y577926D01*
X1459531Y577634D01*
Y577051D01*
X1459094Y576759D01*
G01X1480524Y577926D02*
Y560426D01*
G01Y563050D02*
X1479651Y561592D01*
X1478340Y560718D01*
X1476812Y560426D01*
X1475066Y561009D01*
X1473756Y562467D01*
X1472882Y564217D01*
X1472664Y566259D01*
X1472882Y568301D01*
X1473756Y570051D01*
X1475066Y571509D01*
X1476812Y572092D01*
X1478340Y571801D01*
X1479432Y571217D01*
X1480524Y570051D01*
G01X1490819Y568301D02*
X1497806D01*
X1497151Y570343D01*
X1496059Y571509D01*
X1494531Y572092D01*
X1493002Y571801D01*
X1491692Y570926D01*
X1490819Y568884D01*
X1490382Y567134D01*
Y565384D01*
X1490819Y563634D01*
X1491911Y561884D01*
X1493221Y560718D01*
X1494749Y560426D01*
X1496277Y561009D01*
X1497806Y562759D01*
G01X1525164Y560426D02*
Y577926D01*
G01Y569176D02*
X1526256Y570926D01*
X1527566Y571801D01*
X1528876Y572092D01*
X1530840Y571509D01*
X1532151Y570343D01*
X1533024Y568301D01*
Y565968D01*
X1532587Y563634D01*
X1531714Y561884D01*
X1530186Y560718D01*
X1528876Y560426D01*
X1527566Y560718D01*
X1526256Y561592D01*
X1525164Y563050D01*
G01X1546594Y560426D02*
X1545284Y560718D01*
X1543974Y561884D01*
X1543100Y563926D01*
X1542664Y566259D01*
X1543100Y568593D01*
X1543974Y570634D01*
X1545284Y571801D01*
X1546594Y572092D01*
X1547904Y571801D01*
X1549214Y570634D01*
X1550087Y568593D01*
X1550306Y566259D01*
X1550087Y563926D01*
X1549214Y561884D01*
X1547904Y560718D01*
X1546594Y560426D01*
G01X1568024D02*
Y572092D01*
G01Y570051D02*
X1567151Y571217D01*
X1565840Y571801D01*
X1564312Y572092D01*
X1562784Y571509D01*
X1561474Y570343D01*
X1560600Y568593D01*
X1560164Y566259D01*
X1560600Y563926D01*
X1561474Y562176D01*
X1562784Y561009D01*
X1564312Y560426D01*
X1565840Y560718D01*
X1567151Y561592D01*
X1568024Y562759D01*
G01X1578537Y560426D02*
Y572092D01*
G01Y569759D02*
X1579629Y570926D01*
X1580721Y571801D01*
X1582249Y572092D01*
X1583340Y571801D01*
X1584651Y570926D01*
G01X1603024Y577926D02*
Y560426D01*
G01Y563050D02*
X1602151Y561592D01*
X1600840Y560718D01*
X1599312Y560426D01*
X1597566Y561009D01*
X1596256Y562467D01*
X1595382Y564217D01*
X1595164Y566259D01*
X1595382Y568301D01*
X1596256Y570051D01*
X1597566Y571509D01*
X1599312Y572092D01*
X1600840Y571801D01*
X1601932Y571217D01*
X1603024Y570051D01*
G01X1634094Y560426D02*
X1632784Y560718D01*
X1631474Y561884D01*
X1630600Y563926D01*
X1630164Y566259D01*
X1630600Y568593D01*
X1631474Y570634D01*
X1632784Y571801D01*
X1634094Y572092D01*
X1635404Y571801D01*
X1636714Y570634D01*
X1637587Y568593D01*
X1637806Y566259D01*
X1637587Y563926D01*
X1636714Y561884D01*
X1635404Y560718D01*
X1634094Y560426D01*
G01X1647882Y572092D02*
Y563926D01*
X1648756Y561884D01*
X1650066Y560718D01*
X1651594Y560426D01*
X1653122Y560718D01*
X1654432Y561884D01*
X1655306Y563926D01*
G01Y560426D02*
Y572092D01*
G01X1669094Y577926D02*
Y560426D01*
G01X1666037Y572092D02*
X1672151D01*
G01X1686594Y560426D02*
Y577926D01*
G01X1704094Y572092D02*
Y560426D01*
G01Y576759D02*
X1703657Y577051D01*
Y577634D01*
X1704094Y577926D01*
X1704531Y577634D01*
Y577051D01*
X1704094Y576759D01*
G01X1717882Y560426D02*
Y572092D01*
G01Y569176D02*
X1718756Y570634D01*
X1720066Y571801D01*
X1721812Y572092D01*
X1723340Y571801D01*
X1724651Y570634D01*
X1725306Y568593D01*
Y560426D01*
G01X1735819Y568301D02*
X1742806D01*
X1742151Y570343D01*
X1741059Y571509D01*
X1739531Y572092D01*
X1738002Y571801D01*
X1736692Y570926D01*
X1735819Y568884D01*
X1735382Y567134D01*
Y565384D01*
X1735819Y563634D01*
X1736911Y561884D01*
X1738221Y560718D01*
X1739749Y560426D01*
X1741277Y561009D01*
X1742806Y562759D01*
G01X1756594Y559843D02*
X1756157Y560134D01*
Y560718D01*
X1756594Y561009D01*
X1757031Y560718D01*
Y560134D01*
X1756594Y559843D01*
G01X1331791Y629143D02*
X1341397Y641976D01*
G01X1336594Y644309D02*
Y626809D01*
G01X1341397Y629143D02*
X1331791Y641976D01*
G01X1330044Y635559D02*
X1343144D01*
G01X1368756D02*
X1374432D01*
G01X1401791Y629726D02*
Y647226D01*
X1406157D01*
X1407904Y646351D01*
X1409214Y645184D01*
X1410306Y643435D01*
X1411179Y641392D01*
X1411397Y638476D01*
X1411179Y635559D01*
X1410306Y633517D01*
X1409214Y631767D01*
X1407904Y630601D01*
X1406157Y629726D01*
X1401791D01*
G01X1420819Y637601D02*
X1427806D01*
X1427151Y639643D01*
X1426059Y640809D01*
X1424531Y641392D01*
X1423002Y641101D01*
X1421692Y640226D01*
X1420819Y638184D01*
X1420382Y636434D01*
Y634684D01*
X1420819Y632934D01*
X1421911Y631184D01*
X1423221Y630018D01*
X1424749Y629726D01*
X1426277Y630309D01*
X1427806Y632059D01*
G01X1437882Y629726D02*
Y641392D01*
G01Y638476D02*
X1438756Y639934D01*
X1440066Y641101D01*
X1441812Y641392D01*
X1443340Y641101D01*
X1444651Y639934D01*
X1445306Y637893D01*
Y629726D01*
G01X1459094D02*
X1457784Y630018D01*
X1456474Y631184D01*
X1455600Y633226D01*
X1455164Y635559D01*
X1455600Y637893D01*
X1456474Y639934D01*
X1457784Y641101D01*
X1459094Y641392D01*
X1460404Y641101D01*
X1461714Y639934D01*
X1462587Y637893D01*
X1462806Y635559D01*
X1462587Y633226D01*
X1461714Y631184D01*
X1460404Y630018D01*
X1459094Y629726D01*
G01X1476594Y647226D02*
Y629726D01*
G01X1473537Y641392D02*
X1479651D01*
G01X1490819Y637601D02*
X1497806D01*
X1497151Y639643D01*
X1496059Y640809D01*
X1494531Y641392D01*
X1493002Y641101D01*
X1491692Y640226D01*
X1490819Y638184D01*
X1490382Y636434D01*
Y634684D01*
X1490819Y632934D01*
X1491911Y631184D01*
X1493221Y630018D01*
X1494749Y629726D01*
X1496277Y630309D01*
X1497806Y632059D01*
G01X1508319Y631767D02*
X1509411Y630601D01*
X1510939Y629726D01*
X1512249D01*
X1513559Y630309D01*
X1514432Y631184D01*
X1514869Y632350D01*
X1514651Y634101D01*
X1513777Y634976D01*
X1509847Y636726D01*
X1508974Y638768D01*
X1509411Y640226D01*
X1510284Y641101D01*
X1511594Y641392D01*
X1512904Y641101D01*
X1514214Y640226D01*
G01X1546594Y647226D02*
Y629726D01*
G01X1543537Y641392D02*
X1549651D01*
G01X1560382Y629726D02*
Y647226D01*
G01Y638768D02*
X1561474Y640226D01*
X1562566Y641101D01*
X1564312Y641392D01*
X1565622Y641101D01*
X1567151Y639934D01*
X1567806Y638184D01*
Y629726D01*
G01X1585524D02*
Y641392D01*
G01Y639351D02*
X1584651Y640517D01*
X1583340Y641101D01*
X1581812Y641392D01*
X1580284Y640809D01*
X1578974Y639643D01*
X1578100Y637893D01*
X1577664Y635559D01*
X1578100Y633226D01*
X1578974Y631476D01*
X1580284Y630309D01*
X1581812Y629726D01*
X1583340Y630018D01*
X1584651Y630892D01*
X1585524Y632059D01*
G01X1599094Y647226D02*
Y629726D01*
G01X1596037Y641392D02*
X1602151D01*
G01X1627544Y647226D02*
X1630600Y629726D01*
X1634094Y647226D01*
X1637587Y629726D01*
X1640644Y647226D01*
G01X1648974D02*
X1654214D01*
G01X1651594D02*
Y629726D01*
G01X1648974D02*
X1654214D01*
G01X1664291D02*
Y647226D01*
X1668657D01*
X1670404Y646351D01*
X1671714Y645184D01*
X1672806Y643435D01*
X1673679Y641392D01*
X1673897Y638476D01*
X1673679Y635559D01*
X1672806Y633517D01*
X1671714Y631767D01*
X1670404Y630601D01*
X1668657Y629726D01*
X1664291D01*
G01X1686594Y647226D02*
Y629726D01*
G01X1681572Y647226D02*
X1691616D01*
G01X1699509Y629726D02*
Y647226D01*
G01X1708679D02*
Y629726D01*
G01Y638476D02*
X1699509D01*
G01X0Y-11811D02*
G03X7874Y-19685I7874J0D01*
G01X37008Y0D02*
G03Y-7874I0J-3937D01*
G01X11811D02*
G03Y0I0J3937D01*
G01X0Y-7874D02*
Y-11811D01*
G01X7874Y-19685D02*
X181690D01*
G01X0Y-7874D02*
X11811D01*
G01X25985Y19685D02*
G03X9449I-8268J0D01*
G01D02*
G03X25985I8268J0D01*
G01D02*
G03X9449I-8268J0D01*
G01D02*
G03X25985I8268J0D01*
G01D02*
G03X9449I-8268J0D01*
G01D02*
G03X25985I8268J0D01*
G01D02*
G03X9449I-8268J0D01*
G01D02*
G03X25985I8268J0D01*
G01X9449D02*
G03X25985I8268J0D01*
G01D02*
G03X9449I-8268J0D01*
G01D02*
G03X25985I8268J0D01*
G01D02*
G03X9449I-8268J0D01*
G01X3937Y0D02*
X173229D01*
G01X0Y3937D02*
G03X3937Y0I3937J0D01*
G01X0Y57874D02*
Y3937D01*
G01X37008Y69685D02*
G03Y61811I0J-3937D01*
G01X11811D02*
G03Y69685I0J3937D01*
G01X25985Y89370D02*
G03X9449I-8268J0D01*
G01D02*
G03X25985I8268J0D01*
G01D02*
G03X9449I-8268J0D01*
G01D02*
G03X25985I8268J0D01*
G01D02*
G03X9449I-8268J0D01*
G01D02*
G03X25985I8268J0D01*
G01D02*
G03X9449I-8268J0D01*
G01D02*
G03X25985I8268J0D01*
G01X9449D02*
G03X25985I8268J0D01*
G01D02*
G03X9449I-8268J0D01*
G01D02*
G03X25985I8268J0D01*
G01D02*
G03X9449I-8268J0D01*
G01X3937Y69685D02*
X173229D01*
G01X0Y73622D02*
G03X3937Y69685I3937J0D01*
G01X0Y127559D02*
Y73622D01*
G01X3937Y61811D02*
G03X0Y57874I0J-3937D01*
G01X173229Y61811D02*
X3937D01*
G01X37008Y139370D02*
G03Y131496I0J-3937D01*
G01X11811D02*
G03Y139370I0J3937D01*
G01X25985Y159055D02*
G03X9449I-8268J0D01*
G01D02*
G03X25985I8268J0D01*
G01D02*
G03X9449I-8268J0D01*
G01D02*
G03X25985I8268J0D01*
G01D02*
G03X9449I-8268J0D01*
G01D02*
G03X25985I8268J0D01*
G01D02*
G03X9449I-8268J0D01*
G01D02*
G03X25985I8268J0D01*
G01X9449D02*
G03X25985I8268J0D01*
G01D02*
G03X9449I-8268J0D01*
G01D02*
G03X25985I8268J0D01*
G01D02*
G03X9449I-8268J0D01*
G01X3937Y139370D02*
X173229D01*
G01X0Y143307D02*
G03X3937Y139370I3937J0D01*
G01X0Y197244D02*
Y143307D01*
G01X3937Y131496D02*
G03X0Y127559I0J-3937D01*
G01X173229Y131496D02*
X3937D01*
G01X37008Y278740D02*
G03Y270866I0J-3937D01*
G01X11811D02*
G03Y278740I0J3937D01*
G01X37008Y209055D02*
G03Y201181I0J-3937D01*
G01X11811D02*
G03Y209055I0J3937D01*
G01X3937Y278740D02*
X173229D01*
G01X0Y282677D02*
G03X3937Y278740I3937J0D01*
G01X25985Y228740D02*
G03X9449I-8268J0D01*
G01D02*
G03X25985I8268J0D01*
G01D02*
G03X9449I-8268J0D01*
G01D02*
G03X25985I8268J0D01*
G01D02*
G03X9449I-8268J0D01*
G01D02*
G03X25985I8268J0D01*
G01D02*
G03X9449I-8268J0D01*
G01D02*
G03X25985I8268J0D01*
G01X9449D02*
G03X25985I8268J0D01*
G01D02*
G03X9449I-8268J0D01*
G01D02*
G03X25985I8268J0D01*
G01D02*
G03X9449I-8268J0D01*
G01X3937Y209055D02*
X173229D01*
G01X0Y212992D02*
G03X3937Y209055I3937J0D01*
G01X0Y266929D02*
Y212992D01*
G01X3937Y270866D02*
G03X0Y266929I0J-3937D01*
G01X173229Y270866D02*
X3937D01*
G01Y201181D02*
G03X0Y197244I0J-3937D01*
G01X173229Y201181D02*
X3937D01*
G01X37008Y348425D02*
G03Y340551I0J-3937D01*
G01X11811D02*
G03Y348425I0J3937D01*
G01X9449Y368110D02*
G03X25985I8268J0D01*
G01X9449D02*
G03X25985I8268J0D01*
G01X9449D02*
G03X25985I8268J0D01*
G01X9449D02*
G03X25985I8268J0D01*
G01X9449D02*
G03X25985I8268J0D01*
G01X9449D02*
G03X25985I8268J0D01*
G01X3937Y348425D02*
X173229D01*
G01X0Y352362D02*
G03X3937Y348425I3937J0D01*
G01X0Y406299D02*
Y352362D01*
G01X25985Y298425D02*
G03X9449I-8268J0D01*
G01D02*
G03X25985I8268J0D01*
G01D02*
G03X9449I-8268J0D01*
G01D02*
G03X25985I8268J0D01*
G01D02*
G03X9449I-8268J0D01*
G01D02*
G03X25985I8268J0D01*
G01D02*
G03X9449I-8268J0D01*
G01D02*
G03X25985I8268J0D01*
G01X9449D02*
G03X25985I8268J0D01*
G01D02*
G03X9449I-8268J0D01*
G01D02*
G03X25985I8268J0D01*
G01D02*
G03X9449I-8268J0D01*
G01X0Y336614D02*
Y282677D01*
G01X3937Y340551D02*
G03X0Y336614I0J-3937D01*
G01X173229Y340551D02*
X3937D01*
G01X37008Y418110D02*
G03Y410236I0J-3937D01*
G01X11811D02*
G03Y418110I0J3937D01*
G01X25985Y437795D02*
G03X9449I-8268J0D01*
G01D02*
G03X25985I8268J0D01*
G01D02*
G03X9449I-8268J0D01*
G01D02*
G03X25985I8268J0D01*
G01D02*
G03X9449I-8268J0D01*
G01D02*
G03X25985I8268J0D01*
G01D02*
G03X9449I-8268J0D01*
G01D02*
G03X25985I8268J0D01*
G01X9449D02*
G03X25985I8268J0D01*
G01D02*
G03X9449I-8268J0D01*
G01D02*
G03X25985I8268J0D01*
G01D02*
G03X9449I-8268J0D01*
G01X3937Y418110D02*
X173229D01*
G01X0Y422047D02*
G03X3937Y418110I3937J0D01*
G01X0Y475984D02*
Y422047D01*
G01X25985Y368110D02*
G03X9449I-8268J0D01*
G01X25985D02*
G03X9449I-8268J0D01*
G01X25985D02*
G03X9449I-8268J0D01*
G01X25985D02*
G03X9449I-8268J0D01*
G01X25985D02*
G03X9449I-8268J0D01*
G01X25985D02*
G03X9449I-8268J0D01*
G01X3937Y410236D02*
G03X0Y406299I0J-3937D01*
G01X173229Y410236D02*
X3937D01*
G01X37008Y487795D02*
G03Y479921I0J-3937D01*
G01X11811D02*
G03Y487795I0J3937D01*
G01X25985Y507480D02*
G03X9449I-8268J0D01*
G01D02*
G03X25985I8268J0D01*
G01D02*
G03X9449I-8268J0D01*
G01D02*
G03X25985I8268J0D01*
G01D02*
G03X9449I-8268J0D01*
G01D02*
G03X25985I8268J0D01*
G01D02*
G03X9449I-8268J0D01*
G01D02*
G03X25985I8268J0D01*
G01X9449D02*
G03X25985I8268J0D01*
G01D02*
G03X9449I-8268J0D01*
G01D02*
G03X25985I8268J0D01*
G01D02*
G03X9449I-8268J0D01*
G01X3937Y487795D02*
X173229D01*
G01X0Y491732D02*
G03X3937Y487795I3937J0D01*
G01X0Y545669D02*
Y491732D01*
G01X3937Y479921D02*
G03X0Y475984I0J-3937D01*
G01X173229Y479921D02*
X3937D01*
G01X37008Y557480D02*
G03Y549606I0J-3937D01*
G01X11811D02*
G03Y557480I0J3937D01*
G01X25985Y577165D02*
G03X9449I-8268J0D01*
G01D02*
G03X25985I8268J0D01*
G01D02*
G03X9449I-8268J0D01*
G01D02*
G03X25985I8268J0D01*
G01D02*
G03X9449I-8268J0D01*
G01D02*
G03X25985I8268J0D01*
G01D02*
G03X9449I-8268J0D01*
G01D02*
G03X25985I8268J0D01*
G01X9449D02*
G03X25985I8268J0D01*
G01D02*
G03X9449I-8268J0D01*
G01D02*
G03X25985I8268J0D01*
G01D02*
G03X9449I-8268J0D01*
G01X3937Y557480D02*
X173229D01*
G01X0Y561417D02*
G03X3937Y557480I3937J0D01*
G01X0Y615354D02*
Y561417D01*
G01X3937Y549606D02*
G03X0Y545669I0J-3937D01*
G01X173229Y549606D02*
X3937D01*
G01X37008Y627165D02*
G03Y619291I0J-3937D01*
G01X11811D02*
G03Y627165I0J3937D01*
G01X25985Y646850D02*
G03X9449I-8268J0D01*
G01D02*
G03X25985I8268J0D01*
G01D02*
G03X9449I-8268J0D01*
G01D02*
G03X25985I8268J0D01*
G01D02*
G03X9449I-8268J0D01*
G01D02*
G03X25985I8268J0D01*
G01D02*
G03X9449I-8268J0D01*
G01D02*
G03X25985I8268J0D01*
G01X9449D02*
G03X25985I8268J0D01*
G01D02*
G03X9449I-8268J0D01*
G01D02*
G03X25985I8268J0D01*
G01D02*
G03X9449I-8268J0D01*
G01X3937Y627165D02*
X173229D01*
G01X0Y631102D02*
G03X3937Y627165I3937J0D01*
G01X0Y685039D02*
Y631102D01*
G01X3937Y688976D02*
G03X0Y685039I0J-3937D01*
G01X173229Y688976D02*
X3937D01*
G01Y619291D02*
G03X0Y615354I0J-3937D01*
G01X173229Y619291D02*
X3937D01*
G01X37008Y-7874D02*
X140158D01*
G01X196851D02*
G03Y0I0J3937D01*
G01X189564Y-19685D02*
G03X181690I-3937J0D01*
G01X165355Y0D02*
G03Y-7874I0J-3937D01*
G01X140158D02*
G03Y0I0J3937D01*
G01X185040Y18307D02*
G03X177166I-3937J0D01*
G01X189564Y-19685D02*
X539370D01*
G01X165355Y-7874D02*
X196851D01*
G01X211024Y19685D02*
G03X194489I-8267J0D01*
G01D02*
G03X211024I8267J0D01*
G01D02*
G03X194489I-8267J0D01*
G01D02*
G03X211024I8267J0D01*
G01D02*
G03X194489I-8267J0D01*
G01D02*
G03X211024I8267J0D01*
G01D02*
G03X194489I-8267J0D01*
G01D02*
G03X211024I8267J0D01*
G01X194489D02*
G03X211024I8267J0D01*
G01D02*
G03X194489I-8267J0D01*
G01D02*
G03X211024I8267J0D01*
G01D02*
G03X194489I-8267J0D01*
G01X188977Y0D02*
X358268D01*
G01X185040Y3937D02*
G03X188977Y0I3937J0D01*
G01X185040Y57874D02*
Y3937D01*
G01X167717Y19685D02*
G03X151181I-8268J0D01*
G01D02*
G03X167717I8268J0D01*
G01D02*
G03X151181I-8268J0D01*
G01D02*
G03X167717I8268J0D01*
G01D02*
G03X151181I-8268J0D01*
G01D02*
G03X167717I8268J0D01*
G01D02*
G03X151181I-8268J0D01*
G01D02*
G03X167717I8268J0D01*
G01X151181D02*
G03X167717I8268J0D01*
G01D02*
G03X151181I-8268J0D01*
G01D02*
G03X167717I8268J0D01*
G01D02*
G03X151181I-8268J0D01*
G01X177166Y3937D02*
Y57874D01*
G01X173229Y0D02*
G03X177166Y3937I0J3937D01*
G01X185040Y87992D02*
G03X177166I-3937J0D01*
G01Y113189D02*
G03X185040I3937J0D01*
G01X196851Y61811D02*
G03Y69685I0J3937D01*
G01X165355D02*
G03Y61811I0J-3937D01*
G01X140158D02*
G03Y69685I0J3937D01*
G01X177166Y43504D02*
G03X185040I3937J0D01*
G01X167717Y89370D02*
G03X151181I-8268J0D01*
G01D02*
G03X167717I8268J0D01*
G01D02*
G03X151181I-8268J0D01*
G01D02*
G03X167717I8268J0D01*
G01D02*
G03X151181I-8268J0D01*
G01D02*
G03X167717I8268J0D01*
G01D02*
G03X151181I-8268J0D01*
G01D02*
G03X167717I8268J0D01*
G01X151181D02*
G03X167717I8268J0D01*
G01D02*
G03X151181I-8268J0D01*
G01D02*
G03X167717I8268J0D01*
G01D02*
G03X151181I-8268J0D01*
G01X177166Y73622D02*
Y127559D01*
G01X173229Y69685D02*
G03X177166Y73622I0J3937D01*
G01X211024Y89370D02*
G03X194489I-8267J0D01*
G01D02*
G03X211024I8267J0D01*
G01D02*
G03X194489I-8267J0D01*
G01D02*
G03X211024I8267J0D01*
G01D02*
G03X194489I-8267J0D01*
G01D02*
G03X211024I8267J0D01*
G01D02*
G03X194489I-8267J0D01*
G01D02*
G03X211024I8267J0D01*
G01X194489D02*
G03X211024I8267J0D01*
G01D02*
G03X194489I-8267J0D01*
G01D02*
G03X211024I8267J0D01*
G01D02*
G03X194489I-8267J0D01*
G01X188977Y69685D02*
X358268D01*
G01X185040Y73622D02*
G03X188977Y69685I3937J0D01*
G01X185040Y127559D02*
Y73622D01*
G01X188977Y61811D02*
G03X185040Y57874I0J-3937D01*
G01X358268Y61811D02*
X188977D01*
G01X177166Y57874D02*
G03X173229Y61811I-3937J0D01*
G01X185040Y157677D02*
G03X177166I-3937J0D01*
G01Y182874D02*
G03X185040I3937J0D01*
G01X196851Y131496D02*
G03Y139370I0J3937D01*
G01X165355D02*
G03Y131496I0J-3937D01*
G01X140158D02*
G03Y139370I0J3937D01*
G01X167717Y159055D02*
G03X151181I-8268J0D01*
G01D02*
G03X167717I8268J0D01*
G01D02*
G03X151181I-8268J0D01*
G01D02*
G03X167717I8268J0D01*
G01D02*
G03X151181I-8268J0D01*
G01D02*
G03X167717I8268J0D01*
G01D02*
G03X151181I-8268J0D01*
G01D02*
G03X167717I8268J0D01*
G01X151181D02*
G03X167717I8268J0D01*
G01D02*
G03X151181I-8268J0D01*
G01D02*
G03X167717I8268J0D01*
G01D02*
G03X151181I-8268J0D01*
G01X177166Y143307D02*
Y197244D01*
G01X173229Y139370D02*
G03X177166Y143307I0J3937D01*
G01Y127559D02*
G03X173229Y131496I-3937J0D01*
G01X211024Y159055D02*
G03X194489I-8267J0D01*
G01D02*
G03X211024I8267J0D01*
G01D02*
G03X194489I-8267J0D01*
G01D02*
G03X211024I8267J0D01*
G01D02*
G03X194489I-8267J0D01*
G01D02*
G03X211024I8267J0D01*
G01D02*
G03X194489I-8267J0D01*
G01D02*
G03X211024I8267J0D01*
G01X194489D02*
G03X211024I8267J0D01*
G01D02*
G03X194489I-8267J0D01*
G01D02*
G03X211024I8267J0D01*
G01D02*
G03X194489I-8267J0D01*
G01X188977Y139370D02*
X358268D01*
G01X185040Y143307D02*
G03X188977Y139370I3937J0D01*
G01X185040Y197244D02*
Y143307D01*
G01X188977Y131496D02*
G03X185040Y127559I0J-3937D01*
G01X358268Y131496D02*
X188977D01*
G01X185040Y227362D02*
G03X177166I-3937J0D01*
G01Y252559D02*
G03X185040I3937J0D01*
G01X196851Y270866D02*
G03Y278740I0J3937D01*
G01X165355D02*
G03Y270866I0J-3937D01*
G01X140158D02*
G03Y278740I0J3937D01*
G01X196851Y201181D02*
G03Y209055I0J3937D01*
G01X165355D02*
G03Y201181I0J-3937D01*
G01X140158D02*
G03Y209055I0J3937D01*
G01X173229Y278740D02*
G03X177166Y282677I0J3937D01*
G01X188977Y278740D02*
X358268D01*
G01X185040Y282677D02*
G03X188977Y278740I3937J0D01*
G01X167717Y228740D02*
G03X151181I-8268J0D01*
G01D02*
G03X167717I8268J0D01*
G01D02*
G03X151181I-8268J0D01*
G01D02*
G03X167717I8268J0D01*
G01D02*
G03X151181I-8268J0D01*
G01D02*
G03X167717I8268J0D01*
G01D02*
G03X151181I-8268J0D01*
G01D02*
G03X167717I8268J0D01*
G01X151181D02*
G03X167717I8268J0D01*
G01D02*
G03X151181I-8268J0D01*
G01D02*
G03X167717I8268J0D01*
G01D02*
G03X151181I-8268J0D01*
G01X177166Y212992D02*
Y266929D01*
G01X173229Y209055D02*
G03X177166Y212992I0J3937D01*
G01Y266929D02*
G03X173229Y270866I-3937J0D01*
G01X211024Y228740D02*
G03X194489I-8267J0D01*
G01D02*
G03X211024I8267J0D01*
G01D02*
G03X194489I-8267J0D01*
G01D02*
G03X211024I8267J0D01*
G01D02*
G03X194489I-8267J0D01*
G01D02*
G03X211024I8267J0D01*
G01D02*
G03X194489I-8267J0D01*
G01D02*
G03X211024I8267J0D01*
G01X194489D02*
G03X211024I8267J0D01*
G01D02*
G03X194489I-8267J0D01*
G01D02*
G03X211024I8267J0D01*
G01D02*
G03X194489I-8267J0D01*
G01X188977Y209055D02*
X358268D01*
G01X185040Y212992D02*
G03X188977Y209055I3937J0D01*
G01X185040Y266929D02*
Y212992D01*
G01X188977Y270866D02*
G03X185040Y266929I0J-3937D01*
G01X358268Y270866D02*
X188977D01*
G01X177166Y197244D02*
G03X173229Y201181I-3937J0D01*
G01X188977D02*
G03X185040Y197244I0J-3937D01*
G01X358268Y201181D02*
X188977D01*
G01X185040Y297047D02*
G03X177166I-3937J0D01*
G01Y322244D02*
G03X185040I3937J0D01*
G01X196851Y340551D02*
G03Y348425I0J3937D01*
G01X165355D02*
G03Y340551I0J-3937D01*
G01X140158D02*
G03Y348425I0J3937D01*
G01X151181Y368110D02*
G03X167717I8268J0D01*
G01X151181D02*
G03X167717I8268J0D01*
G01X151181D02*
G03X167717I8268J0D01*
G01X151181D02*
G03X167717I8268J0D01*
G01X151181D02*
G03X167717I8268J0D01*
G01X151181D02*
G03X167717I8268J0D01*
G01X177166Y352362D02*
Y406299D01*
G01X173229Y348425D02*
G03X177166Y352362I0J3937D01*
G01X194489Y368110D02*
G03X211024I8267J0D01*
G01X194489D02*
G03X211024I8267J0D01*
G01X194489D02*
G03X211024I8267J0D01*
G01X194489D02*
G03X211024I8267J0D01*
G01X194489D02*
G03X211024I8267J0D01*
G01X194489D02*
G03X211024I8267J0D01*
G01X188977Y348425D02*
X358268D01*
G01X185040Y352362D02*
G03X188977Y348425I3937J0D01*
G01X185040Y406299D02*
Y352362D01*
G01X167717Y298425D02*
G03X151181I-8268J0D01*
G01D02*
G03X167717I8268J0D01*
G01D02*
G03X151181I-8268J0D01*
G01D02*
G03X167717I8268J0D01*
G01D02*
G03X151181I-8268J0D01*
G01D02*
G03X167717I8268J0D01*
G01D02*
G03X151181I-8268J0D01*
G01D02*
G03X167717I8268J0D01*
G01X151181D02*
G03X167717I8268J0D01*
G01D02*
G03X151181I-8268J0D01*
G01D02*
G03X167717I8268J0D01*
G01D02*
G03X151181I-8268J0D01*
G01X177166Y282677D02*
Y336614D01*
G01D02*
G03X173229Y340551I-3937J0D01*
G01X211024Y298425D02*
G03X194489I-8267J0D01*
G01D02*
G03X211024I8267J0D01*
G01D02*
G03X194489I-8267J0D01*
G01D02*
G03X211024I8267J0D01*
G01D02*
G03X194489I-8267J0D01*
G01D02*
G03X211024I8267J0D01*
G01D02*
G03X194489I-8267J0D01*
G01D02*
G03X211024I8267J0D01*
G01X194489D02*
G03X211024I8267J0D01*
G01D02*
G03X194489I-8267J0D01*
G01D02*
G03X211024I8267J0D01*
G01D02*
G03X194489I-8267J0D01*
G01X185040Y336614D02*
Y282677D01*
G01X188977Y340551D02*
G03X185040Y336614I0J-3937D01*
G01X358268Y340551D02*
X188977D01*
G01X185040Y436417D02*
G03X177166I-3937J0D01*
G01X185040Y366732D02*
G03X177166I-3937J0D01*
G01Y391929D02*
G03X185040I3937J0D01*
G01X196851Y410236D02*
G03Y418110I0J3937D01*
G01X165355D02*
G03Y410236I0J-3937D01*
G01X140158D02*
G03Y418110I0J3937D01*
G01X167717Y437795D02*
G03X151181I-8268J0D01*
G01D02*
G03X167717I8268J0D01*
G01D02*
G03X151181I-8268J0D01*
G01D02*
G03X167717I8268J0D01*
G01D02*
G03X151181I-8268J0D01*
G01D02*
G03X167717I8268J0D01*
G01D02*
G03X151181I-8268J0D01*
G01D02*
G03X167717I8268J0D01*
G01X151181D02*
G03X167717I8268J0D01*
G01D02*
G03X151181I-8268J0D01*
G01D02*
G03X167717I8268J0D01*
G01D02*
G03X151181I-8268J0D01*
G01X177166Y422047D02*
Y475984D01*
G01X173229Y418110D02*
G03X177166Y422047I0J3937D01*
G01X211024Y437795D02*
G03X194489I-8267J0D01*
G01D02*
G03X211024I8267J0D01*
G01D02*
G03X194489I-8267J0D01*
G01D02*
G03X211024I8267J0D01*
G01D02*
G03X194489I-8267J0D01*
G01D02*
G03X211024I8267J0D01*
G01D02*
G03X194489I-8267J0D01*
G01D02*
G03X211024I8267J0D01*
G01X194489D02*
G03X211024I8267J0D01*
G01D02*
G03X194489I-8267J0D01*
G01D02*
G03X211024I8267J0D01*
G01D02*
G03X194489I-8267J0D01*
G01X188977Y418110D02*
X358268D01*
G01X185040Y422047D02*
G03X188977Y418110I3937J0D01*
G01X185040Y475984D02*
Y422047D01*
G01X167717Y368110D02*
G03X151181I-8268J0D01*
G01X167717D02*
G03X151181I-8268J0D01*
G01X167717D02*
G03X151181I-8268J0D01*
G01X167717D02*
G03X151181I-8268J0D01*
G01X167717D02*
G03X151181I-8268J0D01*
G01X167717D02*
G03X151181I-8268J0D01*
G01X177166Y406299D02*
G03X173229Y410236I-3937J0D01*
G01X211024Y368110D02*
G03X194489I-8267J0D01*
G01X211024D02*
G03X194489I-8267J0D01*
G01X211024D02*
G03X194489I-8267J0D01*
G01X211024D02*
G03X194489I-8267J0D01*
G01X211024D02*
G03X194489I-8267J0D01*
G01X211024D02*
G03X194489I-8267J0D01*
G01X188977Y410236D02*
G03X185040Y406299I0J-3937D01*
G01X358268Y410236D02*
X188977D01*
G01X185040Y506102D02*
G03X177166I-3937J0D01*
G01Y531299D02*
G03X185040I3937J0D01*
G01X177166Y461614D02*
G03X185040I3937J0D01*
G01X196851Y479921D02*
G03Y487795I0J3937D01*
G01X165355D02*
G03Y479921I0J-3937D01*
G01X140158D02*
G03Y487795I0J3937D01*
G01X167717Y507480D02*
G03X151181I-8268J0D01*
G01D02*
G03X167717I8268J0D01*
G01D02*
G03X151181I-8268J0D01*
G01D02*
G03X167717I8268J0D01*
G01D02*
G03X151181I-8268J0D01*
G01D02*
G03X167717I8268J0D01*
G01D02*
G03X151181I-8268J0D01*
G01D02*
G03X167717I8268J0D01*
G01X151181D02*
G03X167717I8268J0D01*
G01D02*
G03X151181I-8268J0D01*
G01D02*
G03X167717I8268J0D01*
G01D02*
G03X151181I-8268J0D01*
G01X177166Y491732D02*
Y545669D01*
G01X173229Y487795D02*
G03X177166Y491732I0J3937D01*
G01X211024Y507480D02*
G03X194489I-8267J0D01*
G01D02*
G03X211024I8267J0D01*
G01D02*
G03X194489I-8267J0D01*
G01D02*
G03X211024I8267J0D01*
G01D02*
G03X194489I-8267J0D01*
G01D02*
G03X211024I8267J0D01*
G01D02*
G03X194489I-8267J0D01*
G01D02*
G03X211024I8267J0D01*
G01X194489D02*
G03X211024I8267J0D01*
G01D02*
G03X194489I-8267J0D01*
G01D02*
G03X211024I8267J0D01*
G01D02*
G03X194489I-8267J0D01*
G01X188977Y487795D02*
X358268D01*
G01X185040Y491732D02*
G03X188977Y487795I3937J0D01*
G01X185040Y545669D02*
Y491732D01*
G01X177166Y475984D02*
G03X173229Y479921I-3937J0D01*
G01X188977D02*
G03X185040Y475984I0J-3937D01*
G01X358268Y479921D02*
X188977D01*
G01X185040Y575787D02*
G03X177166I-3937J0D01*
G01Y600984D02*
G03X185040I3937J0D01*
G01X196851Y549606D02*
G03Y557480I0J3937D01*
G01X165355D02*
G03Y549606I0J-3937D01*
G01X140158D02*
G03Y557480I0J3937D01*
G01X167717Y577165D02*
G03X151181I-8268J0D01*
G01D02*
G03X167717I8268J0D01*
G01D02*
G03X151181I-8268J0D01*
G01D02*
G03X167717I8268J0D01*
G01D02*
G03X151181I-8268J0D01*
G01D02*
G03X167717I8268J0D01*
G01D02*
G03X151181I-8268J0D01*
G01D02*
G03X167717I8268J0D01*
G01X151181D02*
G03X167717I8268J0D01*
G01D02*
G03X151181I-8268J0D01*
G01D02*
G03X167717I8268J0D01*
G01D02*
G03X151181I-8268J0D01*
G01X177166Y561417D02*
Y615354D01*
G01X173229Y557480D02*
G03X177166Y561417I0J3937D01*
G01X211024Y577165D02*
G03X194489I-8267J0D01*
G01D02*
G03X211024I8267J0D01*
G01D02*
G03X194489I-8267J0D01*
G01D02*
G03X211024I8267J0D01*
G01D02*
G03X194489I-8267J0D01*
G01D02*
G03X211024I8267J0D01*
G01D02*
G03X194489I-8267J0D01*
G01D02*
G03X211024I8267J0D01*
G01X194489D02*
G03X211024I8267J0D01*
G01D02*
G03X194489I-8267J0D01*
G01D02*
G03X211024I8267J0D01*
G01D02*
G03X194489I-8267J0D01*
G01X188977Y557480D02*
X358268D01*
G01X185040Y561417D02*
G03X188977Y557480I3937J0D01*
G01X185040Y615354D02*
Y561417D01*
G01X177166Y545669D02*
G03X173229Y549606I-3937J0D01*
G01X188977D02*
G03X185040Y545669I0J-3937D01*
G01X358268Y549606D02*
X188977D01*
G01X185040Y645472D02*
G03X177166I-3937J0D01*
G01Y670669D02*
G03X185040I3937J0D01*
G01X196851Y619291D02*
G03Y627165I0J3937D01*
G01X165355D02*
G03Y619291I0J-3937D01*
G01X140158D02*
G03Y627165I0J3937D01*
G01X167717Y646850D02*
G03X151181I-8268J0D01*
G01D02*
G03X167717I8268J0D01*
G01D02*
G03X151181I-8268J0D01*
G01D02*
G03X167717I8268J0D01*
G01D02*
G03X151181I-8268J0D01*
G01D02*
G03X167717I8268J0D01*
G01D02*
G03X151181I-8268J0D01*
G01D02*
G03X167717I8268J0D01*
G01X151181D02*
G03X167717I8268J0D01*
G01D02*
G03X151181I-8268J0D01*
G01D02*
G03X167717I8268J0D01*
G01D02*
G03X151181I-8268J0D01*
G01X177166Y631102D02*
Y685039D01*
G01X173229Y627165D02*
G03X177166Y631102I0J3937D01*
G01Y685039D02*
G03X173229Y688976I-3937J0D01*
G01X211024Y646850D02*
G03X194489I-8267J0D01*
G01D02*
G03X211024I8267J0D01*
G01D02*
G03X194489I-8267J0D01*
G01D02*
G03X211024I8267J0D01*
G01D02*
G03X194489I-8267J0D01*
G01D02*
G03X211024I8267J0D01*
G01D02*
G03X194489I-8267J0D01*
G01D02*
G03X211024I8267J0D01*
G01X194489D02*
G03X211024I8267J0D01*
G01D02*
G03X194489I-8267J0D01*
G01D02*
G03X211024I8267J0D01*
G01D02*
G03X194489I-8267J0D01*
G01X188977Y627165D02*
X358268D01*
G01X185040Y631102D02*
G03X188977Y627165I3937J0D01*
G01X185040Y685039D02*
Y631102D01*
G01X188977Y688976D02*
G03X185040Y685039I0J-3937D01*
G01X358268Y688976D02*
X188977D01*
G01X177166Y615354D02*
G03X173229Y619291I-3937J0D01*
G01X188977D02*
G03X185040Y615354I0J-3937D01*
G01X358268Y619291D02*
X188977D01*
G01X222048Y0D02*
G03Y-7874I0J-3937D01*
G01D02*
X325197D01*
G01X222048Y69685D02*
G03Y61811I0J-3937D01*
G01Y139370D02*
G03Y131496I0J-3937D01*
G01Y278740D02*
G03Y270866I0J-3937D01*
G01Y209055D02*
G03Y201181I0J-3937D01*
G01Y348425D02*
G03Y340551I0J-3937D01*
G01Y418110D02*
G03Y410236I0J-3937D01*
G01Y487795D02*
G03Y479921I0J-3937D01*
G01Y557480D02*
G03Y549606I0J-3937D01*
G01Y627165D02*
G03Y619291I0J-3937D01*
G01X370079Y18307D02*
G03X362205I-3937J0D01*
G01X350394Y0D02*
G03Y-7874I0J-3937D01*
G01X325197D02*
G03Y0I0J3937D01*
G01X350394Y-7874D02*
X381890D01*
G01X352756Y19685D02*
G03X336221I-8267J0D01*
G01D02*
G03X352756I8268J0D01*
G01D02*
G03X336221I-8267J0D01*
G01D02*
G03X352756I8268J0D01*
G01D02*
G03X336221I-8267J0D01*
G01D02*
G03X352756I8268J0D01*
G01D02*
G03X336221I-8267J0D01*
G01D02*
G03X352756I8268J0D01*
G01X336221D02*
G03X352756I8268J0D01*
G01D02*
G03X336221I-8267J0D01*
G01D02*
G03X352756I8268J0D01*
G01D02*
G03X336221I-8267J0D01*
G01X362205Y3937D02*
Y57874D01*
G01X358268Y0D02*
G03X362205Y3937I0J3937D01*
G01X370079Y87992D02*
G03X362205I-3937J0D01*
G01Y113189D02*
G03X370079I3937J0D01*
G01X362205Y43504D02*
G03X370079I3937J0D01*
G01X350394Y69685D02*
G03Y61811I0J-3937D01*
G01X325197D02*
G03Y69685I0J3937D01*
G01X352756Y89370D02*
G03X336221I-8267J0D01*
G01D02*
G03X352756I8268J0D01*
G01D02*
G03X336221I-8267J0D01*
G01D02*
G03X352756I8268J0D01*
G01D02*
G03X336221I-8267J0D01*
G01D02*
G03X352756I8268J0D01*
G01D02*
G03X336221I-8267J0D01*
G01D02*
G03X352756I8268J0D01*
G01X336221D02*
G03X352756I8268J0D01*
G01D02*
G03X336221I-8267J0D01*
G01D02*
G03X352756I8268J0D01*
G01D02*
G03X336221I-8267J0D01*
G01X362205Y73622D02*
Y127559D01*
G01X358268Y69685D02*
G03X362205Y73622I0J3937D01*
G01Y57874D02*
G03X358268Y61811I-3937J0D01*
G01X370079Y157677D02*
G03X362205I-3937J0D01*
G01Y182874D02*
G03X370079I3937J0D01*
G01X350394Y139370D02*
G03Y131496I0J-3937D01*
G01X325197D02*
G03Y139370I0J3937D01*
G01X352756Y159055D02*
G03X336221I-8267J0D01*
G01D02*
G03X352756I8268J0D01*
G01D02*
G03X336221I-8267J0D01*
G01D02*
G03X352756I8268J0D01*
G01D02*
G03X336221I-8267J0D01*
G01D02*
G03X352756I8268J0D01*
G01D02*
G03X336221I-8267J0D01*
G01D02*
G03X352756I8268J0D01*
G01X336221D02*
G03X352756I8268J0D01*
G01D02*
G03X336221I-8267J0D01*
G01D02*
G03X352756I8268J0D01*
G01D02*
G03X336221I-8267J0D01*
G01X362205Y143307D02*
Y197244D01*
G01X358268Y139370D02*
G03X362205Y143307I0J3937D01*
G01Y127559D02*
G03X358268Y131496I-3937J0D01*
G01X370079Y227362D02*
G03X362205I-3937J0D01*
G01Y252559D02*
G03X370079I3937J0D01*
G01X350394Y278740D02*
G03Y270866I0J-3937D01*
G01X325197D02*
G03Y278740I0J3937D01*
G01X350394Y209055D02*
G03Y201181I0J-3937D01*
G01X325197D02*
G03Y209055I0J3937D01*
G01X358268Y278740D02*
G03X362205Y282677I0J3937D01*
G01X352756Y228740D02*
G03X336221I-8267J0D01*
G01D02*
G03X352756I8268J0D01*
G01D02*
G03X336221I-8267J0D01*
G01D02*
G03X352756I8268J0D01*
G01D02*
G03X336221I-8267J0D01*
G01D02*
G03X352756I8268J0D01*
G01D02*
G03X336221I-8267J0D01*
G01D02*
G03X352756I8268J0D01*
G01X336221D02*
G03X352756I8268J0D01*
G01D02*
G03X336221I-8267J0D01*
G01D02*
G03X352756I8268J0D01*
G01D02*
G03X336221I-8267J0D01*
G01X362205Y212992D02*
Y266929D01*
G01X358268Y209055D02*
G03X362205Y212992I0J3937D01*
G01Y266929D02*
G03X358268Y270866I-3937J0D01*
G01X362205Y197244D02*
G03X358268Y201181I-3937J0D01*
G01X370079Y297047D02*
G03X362205I-3937J0D01*
G01Y322244D02*
G03X370079I3937J0D01*
G01X350394Y348425D02*
G03Y340551I0J-3937D01*
G01X325197D02*
G03Y348425I0J3937D01*
G01X336221Y368110D02*
G03X352756I8268J0D01*
G01X336221D02*
G03X352756I8268J0D01*
G01X336221D02*
G03X352756I8268J0D01*
G01X336221D02*
G03X352756I8268J0D01*
G01X336221D02*
G03X352756I8268J0D01*
G01X336221D02*
G03X352756I8268J0D01*
G01X362205Y352362D02*
Y406299D01*
G01X358268Y348425D02*
G03X362205Y352362I0J3937D01*
G01X352756Y298425D02*
G03X336221I-8267J0D01*
G01D02*
G03X352756I8268J0D01*
G01D02*
G03X336221I-8267J0D01*
G01D02*
G03X352756I8268J0D01*
G01D02*
G03X336221I-8267J0D01*
G01D02*
G03X352756I8268J0D01*
G01D02*
G03X336221I-8267J0D01*
G01D02*
G03X352756I8268J0D01*
G01X336221D02*
G03X352756I8268J0D01*
G01D02*
G03X336221I-8267J0D01*
G01D02*
G03X352756I8268J0D01*
G01D02*
G03X336221I-8267J0D01*
G01X362205Y282677D02*
Y336614D01*
G01D02*
G03X358268Y340551I-3937J0D01*
G01X370079Y436417D02*
G03X362205I-3937J0D01*
G01X370079Y366732D02*
G03X362205I-3937J0D01*
G01Y391929D02*
G03X370079I3937J0D01*
G01X350394Y418110D02*
G03Y410236I0J-3937D01*
G01X325197D02*
G03Y418110I0J3937D01*
G01X352756Y437795D02*
G03X336221I-8267J0D01*
G01D02*
G03X352756I8268J0D01*
G01D02*
G03X336221I-8267J0D01*
G01D02*
G03X352756I8268J0D01*
G01D02*
G03X336221I-8267J0D01*
G01D02*
G03X352756I8268J0D01*
G01D02*
G03X336221I-8267J0D01*
G01D02*
G03X352756I8268J0D01*
G01X336221D02*
G03X352756I8268J0D01*
G01D02*
G03X336221I-8267J0D01*
G01D02*
G03X352756I8268J0D01*
G01D02*
G03X336221I-8267J0D01*
G01X362205Y422047D02*
Y475984D01*
G01X358268Y418110D02*
G03X362205Y422047I0J3937D01*
G01X352756Y368110D02*
G03X336221I-8267J0D01*
G01X352756D02*
G03X336221I-8267J0D01*
G01X352756D02*
G03X336221I-8267J0D01*
G01X352756D02*
G03X336221I-8267J0D01*
G01X352756D02*
G03X336221I-8267J0D01*
G01X352756D02*
G03X336221I-8267J0D01*
G01X362205Y406299D02*
G03X358268Y410236I-3937J0D01*
G01X370079Y506102D02*
G03X362205I-3937J0D01*
G01Y531299D02*
G03X370079I3937J0D01*
G01X362205Y461614D02*
G03X370079I3937J0D01*
G01X350394Y487795D02*
G03Y479921I0J-3937D01*
G01X325197D02*
G03Y487795I0J3937D01*
G01X352756Y507480D02*
G03X336221I-8267J0D01*
G01D02*
G03X352756I8268J0D01*
G01D02*
G03X336221I-8267J0D01*
G01D02*
G03X352756I8268J0D01*
G01D02*
G03X336221I-8267J0D01*
G01D02*
G03X352756I8268J0D01*
G01D02*
G03X336221I-8267J0D01*
G01D02*
G03X352756I8268J0D01*
G01X336221D02*
G03X352756I8268J0D01*
G01D02*
G03X336221I-8267J0D01*
G01D02*
G03X352756I8268J0D01*
G01D02*
G03X336221I-8267J0D01*
G01X362205Y491732D02*
Y545669D01*
G01X358268Y487795D02*
G03X362205Y491732I0J3937D01*
G01Y475984D02*
G03X358268Y479921I-3937J0D01*
G01X370079Y575787D02*
G03X362205I-3937J0D01*
G01Y600984D02*
G03X370079I3937J0D01*
G01X350394Y557480D02*
G03Y549606I0J-3937D01*
G01X325197D02*
G03Y557480I0J3937D01*
G01X352756Y577165D02*
G03X336221I-8267J0D01*
G01D02*
G03X352756I8268J0D01*
G01D02*
G03X336221I-8267J0D01*
G01D02*
G03X352756I8268J0D01*
G01D02*
G03X336221I-8267J0D01*
G01D02*
G03X352756I8268J0D01*
G01D02*
G03X336221I-8267J0D01*
G01D02*
G03X352756I8268J0D01*
G01X336221D02*
G03X352756I8268J0D01*
G01D02*
G03X336221I-8267J0D01*
G01D02*
G03X352756I8268J0D01*
G01D02*
G03X336221I-8267J0D01*
G01X362205Y561417D02*
Y615354D01*
G01X358268Y557480D02*
G03X362205Y561417I0J3937D01*
G01Y545669D02*
G03X358268Y549606I-3937J0D01*
G01X370079Y645472D02*
G03X362205I-3937J0D01*
G01Y670669D02*
G03X370079I3937J0D01*
G01X350394Y627165D02*
G03Y619291I0J-3937D01*
G01X325197D02*
G03Y627165I0J3937D01*
G01X352756Y646850D02*
G03X336221I-8267J0D01*
G01D02*
G03X352756I8268J0D01*
G01D02*
G03X336221I-8267J0D01*
G01D02*
G03X352756I8268J0D01*
G01D02*
G03X336221I-8267J0D01*
G01D02*
G03X352756I8268J0D01*
G01D02*
G03X336221I-8267J0D01*
G01D02*
G03X352756I8268J0D01*
G01X336221D02*
G03X352756I8268J0D01*
G01D02*
G03X336221I-8267J0D01*
G01D02*
G03X352756I8268J0D01*
G01D02*
G03X336221I-8267J0D01*
G01X362205Y631102D02*
Y685039D01*
G01X358268Y627165D02*
G03X362205Y631102I0J3937D01*
G01Y685039D02*
G03X358268Y688976I-3937J0D01*
G01X362205Y615354D02*
G03X358268Y619291I-3937J0D01*
G01X407087Y0D02*
G03Y-7874I0J-3937D01*
G01X381890D02*
G03Y0I0J3937D01*
G01X407087Y-7874D02*
X510237D01*
G01X396063Y19685D02*
G03X379528I-8268J0D01*
G01D02*
G03X396063I8267J0D01*
G01D02*
G03X379528I-8268J0D01*
G01D02*
G03X396063I8267J0D01*
G01D02*
G03X379528I-8268J0D01*
G01D02*
G03X396063I8267J0D01*
G01D02*
G03X379528I-8268J0D01*
G01D02*
G03X396063I8267J0D01*
G01X379528D02*
G03X396063I8267J0D01*
G01D02*
G03X379528I-8268J0D01*
G01D02*
G03X396063I8267J0D01*
G01D02*
G03X379528I-8268J0D01*
G01X374016Y0D02*
X543307D01*
G01X370079Y3937D02*
G03X374016Y0I3937J0D01*
G01X370079Y57874D02*
Y3937D01*
G01X407087Y69685D02*
G03Y61811I0J-3937D01*
G01X381890D02*
G03Y69685I0J3937D01*
G01X396063Y89370D02*
G03X379528I-8268J0D01*
G01D02*
G03X396063I8267J0D01*
G01D02*
G03X379528I-8268J0D01*
G01D02*
G03X396063I8267J0D01*
G01D02*
G03X379528I-8268J0D01*
G01D02*
G03X396063I8267J0D01*
G01D02*
G03X379528I-8268J0D01*
G01D02*
G03X396063I8267J0D01*
G01X379528D02*
G03X396063I8267J0D01*
G01D02*
G03X379528I-8268J0D01*
G01D02*
G03X396063I8267J0D01*
G01D02*
G03X379528I-8268J0D01*
G01X374016Y69685D02*
X543307D01*
G01X370079Y73622D02*
G03X374016Y69685I3937J0D01*
G01X370079Y127559D02*
Y73622D01*
G01X374016Y61811D02*
G03X370079Y57874I0J-3937D01*
G01X543307Y61811D02*
X374016D01*
G01X407087Y139370D02*
G03Y131496I0J-3937D01*
G01X381890D02*
G03Y139370I0J3937D01*
G01X396063Y159055D02*
G03X379528I-8268J0D01*
G01D02*
G03X396063I8267J0D01*
G01D02*
G03X379528I-8268J0D01*
G01D02*
G03X396063I8267J0D01*
G01D02*
G03X379528I-8268J0D01*
G01D02*
G03X396063I8267J0D01*
G01D02*
G03X379528I-8268J0D01*
G01D02*
G03X396063I8267J0D01*
G01X379528D02*
G03X396063I8267J0D01*
G01D02*
G03X379528I-8268J0D01*
G01D02*
G03X396063I8267J0D01*
G01D02*
G03X379528I-8268J0D01*
G01X374016Y139370D02*
X543307D01*
G01X370079Y143307D02*
G03X374016Y139370I3937J0D01*
G01X370079Y197244D02*
Y143307D01*
G01X374016Y131496D02*
G03X370079Y127559I0J-3937D01*
G01X543307Y131496D02*
X374016D01*
G01X407087Y278740D02*
G03Y270866I0J-3937D01*
G01X381890D02*
G03Y278740I0J3937D01*
G01X407087Y209055D02*
G03Y201181I0J-3937D01*
G01X381890D02*
G03Y209055I0J3937D01*
G01X374016Y278740D02*
X543307D01*
G01X370079Y282677D02*
G03X374016Y278740I3937J0D01*
G01X396063Y228740D02*
G03X379528I-8268J0D01*
G01D02*
G03X396063I8267J0D01*
G01D02*
G03X379528I-8268J0D01*
G01D02*
G03X396063I8267J0D01*
G01D02*
G03X379528I-8268J0D01*
G01D02*
G03X396063I8267J0D01*
G01D02*
G03X379528I-8268J0D01*
G01D02*
G03X396063I8267J0D01*
G01X379528D02*
G03X396063I8267J0D01*
G01D02*
G03X379528I-8268J0D01*
G01D02*
G03X396063I8267J0D01*
G01D02*
G03X379528I-8268J0D01*
G01X374016Y209055D02*
X543307D01*
G01X370079Y212992D02*
G03X374016Y209055I3937J0D01*
G01X370079Y266929D02*
Y212992D01*
G01X374016Y270866D02*
G03X370079Y266929I0J-3937D01*
G01X543307Y270866D02*
X374016D01*
G01Y201181D02*
G03X370079Y197244I0J-3937D01*
G01X543307Y201181D02*
X374016D01*
G01X407087Y348425D02*
G03Y340551I0J-3937D01*
G01X381890D02*
G03Y348425I0J3937D01*
G01X379528Y368110D02*
G03X396063I8267J0D01*
G01X379528D02*
G03X396063I8267J0D01*
G01X379528D02*
G03X396063I8267J0D01*
G01X379528D02*
G03X396063I8267J0D01*
G01X379528D02*
G03X396063I8267J0D01*
G01X379528D02*
G03X396063I8267J0D01*
G01X374016Y348425D02*
X543307D01*
G01X370079Y352362D02*
G03X374016Y348425I3937J0D01*
G01X370079Y406299D02*
Y352362D01*
G01X396063Y298425D02*
G03X379528I-8268J0D01*
G01D02*
G03X396063I8267J0D01*
G01D02*
G03X379528I-8268J0D01*
G01D02*
G03X396063I8267J0D01*
G01D02*
G03X379528I-8268J0D01*
G01D02*
G03X396063I8267J0D01*
G01D02*
G03X379528I-8268J0D01*
G01D02*
G03X396063I8267J0D01*
G01X379528D02*
G03X396063I8267J0D01*
G01D02*
G03X379528I-8268J0D01*
G01D02*
G03X396063I8267J0D01*
G01D02*
G03X379528I-8268J0D01*
G01X370079Y336614D02*
Y282677D01*
G01X374016Y340551D02*
G03X370079Y336614I0J-3937D01*
G01X543307Y340551D02*
X374016D01*
G01X407087Y418110D02*
G03Y410236I0J-3937D01*
G01X381890D02*
G03Y418110I0J3937D01*
G01X396063Y437795D02*
G03X379528I-8268J0D01*
G01D02*
G03X396063I8267J0D01*
G01D02*
G03X379528I-8268J0D01*
G01D02*
G03X396063I8267J0D01*
G01D02*
G03X379528I-8268J0D01*
G01D02*
G03X396063I8267J0D01*
G01D02*
G03X379528I-8268J0D01*
G01D02*
G03X396063I8267J0D01*
G01X379528D02*
G03X396063I8267J0D01*
G01D02*
G03X379528I-8268J0D01*
G01D02*
G03X396063I8267J0D01*
G01D02*
G03X379528I-8268J0D01*
G01X374016Y418110D02*
X543307D01*
G01X370079Y422047D02*
G03X374016Y418110I3937J0D01*
G01X370079Y475984D02*
Y422047D01*
G01X396063Y368110D02*
G03X379528I-8268J0D01*
G01X396063D02*
G03X379528I-8268J0D01*
G01X396063D02*
G03X379528I-8268J0D01*
G01X396063D02*
G03X379528I-8268J0D01*
G01X396063D02*
G03X379528I-8268J0D01*
G01X396063D02*
G03X379528I-8268J0D01*
G01X374016Y410236D02*
G03X370079Y406299I0J-3937D01*
G01X543307Y410236D02*
X374016D01*
G01X407087Y487795D02*
G03Y479921I0J-3937D01*
G01X381890D02*
G03Y487795I0J3937D01*
G01X396063Y507480D02*
G03X379528I-8268J0D01*
G01D02*
G03X396063I8267J0D01*
G01D02*
G03X379528I-8268J0D01*
G01D02*
G03X396063I8267J0D01*
G01D02*
G03X379528I-8268J0D01*
G01D02*
G03X396063I8267J0D01*
G01D02*
G03X379528I-8268J0D01*
G01D02*
G03X396063I8267J0D01*
G01X379528D02*
G03X396063I8267J0D01*
G01D02*
G03X379528I-8268J0D01*
G01D02*
G03X396063I8267J0D01*
G01D02*
G03X379528I-8268J0D01*
G01X374016Y487795D02*
X543307D01*
G01X370079Y491732D02*
G03X374016Y487795I3937J0D01*
G01X370079Y545669D02*
Y491732D01*
G01X374016Y479921D02*
G03X370079Y475984I0J-3937D01*
G01X543307Y479921D02*
X374016D01*
G01X407087Y557480D02*
G03Y549606I0J-3937D01*
G01X381890D02*
G03Y557480I0J3937D01*
G01X396063Y577165D02*
G03X379528I-8268J0D01*
G01D02*
G03X396063I8267J0D01*
G01D02*
G03X379528I-8268J0D01*
G01D02*
G03X396063I8267J0D01*
G01D02*
G03X379528I-8268J0D01*
G01D02*
G03X396063I8267J0D01*
G01D02*
G03X379528I-8268J0D01*
G01D02*
G03X396063I8267J0D01*
G01X379528D02*
G03X396063I8267J0D01*
G01D02*
G03X379528I-8268J0D01*
G01D02*
G03X396063I8267J0D01*
G01D02*
G03X379528I-8268J0D01*
G01X374016Y557480D02*
X543307D01*
G01X370079Y561417D02*
G03X374016Y557480I3937J0D01*
G01X370079Y615354D02*
Y561417D01*
G01X374016Y549606D02*
G03X370079Y545669I0J-3937D01*
G01X543307Y549606D02*
X374016D01*
G01X407087Y627165D02*
G03Y619291I0J-3937D01*
G01X381890D02*
G03Y627165I0J3937D01*
G01X396063Y646850D02*
G03X379528I-8268J0D01*
G01D02*
G03X396063I8267J0D01*
G01D02*
G03X379528I-8268J0D01*
G01D02*
G03X396063I8267J0D01*
G01D02*
G03X379528I-8268J0D01*
G01D02*
G03X396063I8267J0D01*
G01D02*
G03X379528I-8268J0D01*
G01D02*
G03X396063I8267J0D01*
G01X379528D02*
G03X396063I8267J0D01*
G01D02*
G03X379528I-8268J0D01*
G01D02*
G03X396063I8267J0D01*
G01D02*
G03X379528I-8268J0D01*
G01X374016Y627165D02*
X543307D01*
G01X370079Y631102D02*
G03X374016Y627165I3937J0D01*
G01X370079Y685039D02*
Y631102D01*
G01X374016Y688976D02*
G03X370079Y685039I0J-3937D01*
G01X543307Y688976D02*
X374016D01*
G01Y619291D02*
G03X370079Y615354I0J-3937D01*
G01X543307Y619291D02*
X374016D01*
G01X510237Y-7874D02*
G03Y0I0J3937D01*
G01X537796Y19685D02*
G03X521260I-8268J0D01*
G01D02*
G03X537796I8268J0D01*
G01D02*
G03X521260I-8268J0D01*
G01D02*
G03X537796I8268J0D01*
G01D02*
G03X521260I-8268J0D01*
G01D02*
G03X537796I8268J0D01*
G01D02*
G03X521260I-8268J0D01*
G01D02*
G03X537796I8268J0D01*
G01X521260D02*
G03X537796I8268J0D01*
G01D02*
G03X521260I-8268J0D01*
G01D02*
G03X537796I8268J0D01*
G01D02*
G03X521260I-8268J0D01*
G01X510237Y61811D02*
G03Y69685I0J3937D01*
G01X537796Y89370D02*
G03X521260I-8268J0D01*
G01D02*
G03X537796I8268J0D01*
G01D02*
G03X521260I-8268J0D01*
G01D02*
G03X537796I8268J0D01*
G01D02*
G03X521260I-8268J0D01*
G01D02*
G03X537796I8268J0D01*
G01D02*
G03X521260I-8268J0D01*
G01D02*
G03X537796I8268J0D01*
G01X521260D02*
G03X537796I8268J0D01*
G01D02*
G03X521260I-8268J0D01*
G01D02*
G03X537796I8268J0D01*
G01D02*
G03X521260I-8268J0D01*
G01X510237Y131496D02*
G03Y139370I0J3937D01*
G01X537796Y159055D02*
G03X521260I-8268J0D01*
G01D02*
G03X537796I8268J0D01*
G01D02*
G03X521260I-8268J0D01*
G01D02*
G03X537796I8268J0D01*
G01D02*
G03X521260I-8268J0D01*
G01D02*
G03X537796I8268J0D01*
G01D02*
G03X521260I-8268J0D01*
G01D02*
G03X537796I8268J0D01*
G01X521260D02*
G03X537796I8268J0D01*
G01D02*
G03X521260I-8268J0D01*
G01D02*
G03X537796I8268J0D01*
G01D02*
G03X521260I-8268J0D01*
G01X510237Y270866D02*
G03Y278740I0J3937D01*
G01Y201181D02*
G03Y209055I0J3937D01*
G01X537796Y228740D02*
G03X521260I-8268J0D01*
G01D02*
G03X537796I8268J0D01*
G01D02*
G03X521260I-8268J0D01*
G01D02*
G03X537796I8268J0D01*
G01D02*
G03X521260I-8268J0D01*
G01D02*
G03X537796I8268J0D01*
G01D02*
G03X521260I-8268J0D01*
G01D02*
G03X537796I8268J0D01*
G01X521260D02*
G03X537796I8268J0D01*
G01D02*
G03X521260I-8268J0D01*
G01D02*
G03X537796I8268J0D01*
G01D02*
G03X521260I-8268J0D01*
G01X510237Y340551D02*
G03Y348425I0J3937D01*
G01X521260Y368110D02*
G03X537796I8268J0D01*
G01X521260D02*
G03X537796I8268J0D01*
G01X521260D02*
G03X537796I8268J0D01*
G01X521260D02*
G03X537796I8268J0D01*
G01X521260D02*
G03X537796I8268J0D01*
G01X521260D02*
G03X537796I8268J0D01*
G01Y298425D02*
G03X521260I-8268J0D01*
G01D02*
G03X537796I8268J0D01*
G01D02*
G03X521260I-8268J0D01*
G01D02*
G03X537796I8268J0D01*
G01D02*
G03X521260I-8268J0D01*
G01D02*
G03X537796I8268J0D01*
G01D02*
G03X521260I-8268J0D01*
G01D02*
G03X537796I8268J0D01*
G01X521260D02*
G03X537796I8268J0D01*
G01D02*
G03X521260I-8268J0D01*
G01D02*
G03X537796I8268J0D01*
G01D02*
G03X521260I-8268J0D01*
G01X510237Y410236D02*
G03Y418110I0J3937D01*
G01X537796Y437795D02*
G03X521260I-8268J0D01*
G01D02*
G03X537796I8268J0D01*
G01D02*
G03X521260I-8268J0D01*
G01D02*
G03X537796I8268J0D01*
G01D02*
G03X521260I-8268J0D01*
G01D02*
G03X537796I8268J0D01*
G01D02*
G03X521260I-8268J0D01*
G01D02*
G03X537796I8268J0D01*
G01X521260D02*
G03X537796I8268J0D01*
G01D02*
G03X521260I-8268J0D01*
G01D02*
G03X537796I8268J0D01*
G01D02*
G03X521260I-8268J0D01*
G01X537796Y368110D02*
G03X521260I-8268J0D01*
G01X537796D02*
G03X521260I-8268J0D01*
G01X537796D02*
G03X521260I-8268J0D01*
G01X537796D02*
G03X521260I-8268J0D01*
G01X537796D02*
G03X521260I-8268J0D01*
G01X537796D02*
G03X521260I-8268J0D01*
G01X510237Y479921D02*
G03Y487795I0J3937D01*
G01X537796Y507480D02*
G03X521260I-8268J0D01*
G01D02*
G03X537796I8268J0D01*
G01D02*
G03X521260I-8268J0D01*
G01D02*
G03X537796I8268J0D01*
G01D02*
G03X521260I-8268J0D01*
G01D02*
G03X537796I8268J0D01*
G01D02*
G03X521260I-8268J0D01*
G01D02*
G03X537796I8268J0D01*
G01X521260D02*
G03X537796I8268J0D01*
G01D02*
G03X521260I-8268J0D01*
G01D02*
G03X537796I8268J0D01*
G01D02*
G03X521260I-8268J0D01*
G01X510237Y549606D02*
G03Y557480I0J3937D01*
G01X537796Y577165D02*
G03X521260I-8268J0D01*
G01D02*
G03X537796I8268J0D01*
G01D02*
G03X521260I-8268J0D01*
G01D02*
G03X537796I8268J0D01*
G01D02*
G03X521260I-8268J0D01*
G01D02*
G03X537796I8268J0D01*
G01D02*
G03X521260I-8268J0D01*
G01D02*
G03X537796I8268J0D01*
G01X521260D02*
G03X537796I8268J0D01*
G01D02*
G03X521260I-8268J0D01*
G01D02*
G03X537796I8268J0D01*
G01D02*
G03X521260I-8268J0D01*
G01X510237Y619291D02*
G03Y627165I0J3937D01*
G01X537796Y646850D02*
G03X521260I-8268J0D01*
G01D02*
G03X537796I8268J0D01*
G01D02*
G03X521260I-8268J0D01*
G01D02*
G03X537796I8268J0D01*
G01D02*
G03X521260I-8268J0D01*
G01D02*
G03X537796I8268J0D01*
G01D02*
G03X521260I-8268J0D01*
G01D02*
G03X537796I8268J0D01*
G01X521260D02*
G03X537796I8268J0D01*
G01D02*
G03X521260I-8268J0D01*
G01D02*
G03X537796I8268J0D01*
G01D02*
G03X521260I-8268J0D01*
G01X539370Y-19685D02*
G03X547244Y-11811I0J7874D01*
G01X535433Y0D02*
G03Y-7874I0J-3937D01*
G01X547244D02*
Y-11811D01*
G01X535433Y-7874D02*
X547244D01*
G01Y3937D02*
Y57874D01*
G01X543307Y0D02*
G03X547244Y3937I0J3937D01*
G01X535433Y69685D02*
G03Y61811I0J-3937D01*
G01X547244Y73622D02*
Y127559D01*
G01X543307Y69685D02*
G03X547244Y73622I0J3937D01*
G01Y57874D02*
G03X543307Y61811I-3937J0D01*
G01X535433Y139370D02*
G03Y131496I0J-3937D01*
G01X547244Y143307D02*
Y197244D01*
G01X543307Y139370D02*
G03X547244Y143307I0J3937D01*
G01Y127559D02*
G03X543307Y131496I-3937J0D01*
G01X535433Y278740D02*
G03Y270866I0J-3937D01*
G01Y209055D02*
G03Y201181I0J-3937D01*
G01X543307Y278740D02*
G03X547244Y282677I0J3937D01*
G01Y212992D02*
Y266929D01*
G01X543307Y209055D02*
G03X547244Y212992I0J3937D01*
G01Y266929D02*
G03X543307Y270866I-3937J0D01*
G01X547244Y197244D02*
G03X543307Y201181I-3937J0D01*
G01X535433Y348425D02*
G03Y340551I0J-3937D01*
G01X547244Y352362D02*
Y406299D01*
G01X543307Y348425D02*
G03X547244Y352362I0J3937D01*
G01Y282677D02*
Y336614D01*
G01D02*
G03X543307Y340551I-3937J0D01*
G01X535433Y418110D02*
G03Y410236I0J-3937D01*
G01X547244Y422047D02*
Y475984D01*
G01X543307Y418110D02*
G03X547244Y422047I0J3937D01*
G01Y406299D02*
G03X543307Y410236I-3937J0D01*
G01X535433Y487795D02*
G03Y479921I0J-3937D01*
G01X547244Y491732D02*
Y545669D01*
G01X543307Y487795D02*
G03X547244Y491732I0J3937D01*
G01Y475984D02*
G03X543307Y479921I-3937J0D01*
G01X535433Y557480D02*
G03Y549606I0J-3937D01*
G01X547244Y561417D02*
Y615354D01*
G01X543307Y557480D02*
G03X547244Y561417I0J3937D01*
G01Y545669D02*
G03X543307Y549606I-3937J0D01*
G01X535433Y627165D02*
G03Y619291I0J-3937D01*
G01X547244Y631102D02*
Y685039D01*
G01X543307Y627165D02*
G03X547244Y631102I0J3937D01*
G01Y685039D02*
G03X543307Y688976I-3937J0D01*
G01X547244Y615354D02*
G03X543307Y619291I-3937J0D01*
M02*
